G04 ================== begin FILE IDENTIFICATION RECORD ==================*
G04 Layout Name:  D:/<user>/Wistron_project/16317-1/gbr/16317-1.brd*
G04 Film Name:    DP_REF_L8*
G04 File Format:  Gerber RS274X*
G04 File Origin:  Cadence Allegro 16.5-S056*
G04 Origin Date:  Fri Jun 09 15:54:12 2017*
G04 *
G04 Layer:  BOARD GEOMETRY/DP_REF_L8_TBL*
G04 Layer:  BOARD GEOMETRY/DP_REF_L8_BOTTOM*
G04 Layer:  BOARD GEOMETRY/PANEL_OUTLINE*
G04 *
G04 Offset:    (0.00 0.00)*
G04 Mirror:    No*
G04 Mode:      Positive*
G04 Rotation:  0*
G04 FullContactRelief:  No*
G04 UndefLineWidth:     6.00*
G04 ================== end FILE IDENTIFICATION RECORD ====================*
%FSLAX35Y35*MOIN*%
%IR0*IPPOS*OFA0.00000B0.00000*MIA0B0*SFA1.00000B1.00000*%
%ADD10C,.02*%
%ADD11C,.005*%
%ADD12C,.006*%
%ADD13C,.0065*%
G75*
%LPD*%
G75*
G54D10*
G01X1985143Y1416035D02*
X2720143D01*
G01X1985143Y1381385D02*
X2720143D01*
G01X1985143Y1485335D02*
Y1381385D01*
G01Y1485335D02*
X2720143D01*
G01X1985143Y1450685D02*
X2720143D01*
G01X2160143Y1485335D02*
Y1381385D01*
G01X2405143Y1485335D02*
Y1381385D01*
G01X2510143Y1485335D02*
Y1381385D01*
G01X2720143Y1485335D02*
Y1381385D01*
G54D11*
G01X138536Y58444D02*
X135513D01*
G01X138414Y59594D02*
X135551D01*
G01X140007Y58757D02*
X138536Y58444D01*
G01X139559Y59838D02*
X138414Y59594D01*
G01X145333Y62216D02*
X140007Y58757D01*
G01X144501Y63048D02*
X139559Y59838D01*
G01X148449Y67014D02*
X145333Y62216D01*
G01X147617Y67846D02*
X144501Y63048D01*
G01X196714Y98363D02*
X148449Y67014D01*
G01X150885Y69969D02*
X147617Y67846D01*
G01X154407Y72256D02*
X153149Y71439D01*
G01X157929Y74544D02*
X156671Y73727D01*
G01X161452Y76832D02*
X160194Y76015D01*
G01X196266Y99444D02*
X163716Y78302D01*
G01X138414Y59594D02*
X135551D01*
G01X138536Y58444D02*
X135513D01*
G01X139559Y59838D02*
X138414Y59594D01*
G01X140007Y58757D02*
X138536Y58444D01*
G01X144501Y63048D02*
X139559Y59838D01*
G01X145333Y62216D02*
X140007Y58757D01*
G01X147617Y67846D02*
X144501Y63048D01*
G01X148449Y67014D02*
X145333Y62216D01*
G01X150885Y69969D02*
X147617Y67846D01*
G01X196714Y98363D02*
X148449Y67014D01*
G01X154407Y72256D02*
X153149Y71439D01*
G01X196714Y98363D02*
X148449Y67014D01*
G01X157929Y74544D02*
X156671Y73727D01*
G01X196714Y98363D02*
X148449Y67014D01*
G01X161452Y76832D02*
X160194Y76015D01*
G01X196714Y98363D02*
X148449Y67014D01*
G01X196266Y99444D02*
X163716Y78302D01*
G01X196714Y98363D02*
X148449Y67014D01*
G01X139870Y511200D02*
X135513D01*
G01X139782Y512350D02*
X135551D01*
G01X203763Y520971D02*
X139870Y511200D01*
G01X203344Y522071D02*
X139782Y512350D01*
G01D02*
X135551D01*
G01X139870Y511200D02*
X135513D01*
G01X203344Y522071D02*
X139782Y512350D01*
G01X203763Y520971D02*
X139870Y511200D01*
G01X318053Y918147D02*
X138800Y963956D01*
G01X318276Y919277D02*
X138945Y965106D01*
G01X318276Y919277D02*
X138945Y965106D01*
G01X318053Y918147D02*
X138800Y963956D01*
G01D02*
X135513D01*
G01X138945Y965106D02*
X135551D01*
G01X138945D02*
X135551D01*
G01X138800Y963956D02*
X135513D01*
G01X262061Y58444D02*
X259725D01*
G01X261940Y59594D02*
X259763D01*
G01X268507Y59805D02*
X262061Y58444D01*
G01X268060Y60886D02*
X261940Y59594D01*
G01X406918Y149653D02*
X268507Y59805D01*
G01X406086Y150485D02*
X268060Y60886D01*
G01X261940Y59594D02*
X259763D01*
G01X262061Y58444D02*
X259725D01*
G01X268060Y60886D02*
X261940Y59594D01*
G01X268507Y59805D02*
X262061Y58444D01*
G01X406086Y150485D02*
X268060Y60886D01*
G01X406918Y149653D02*
X268507Y59805D01*
G01X271649Y114289D02*
X196714Y98363D01*
G01X271201Y115370D02*
X196266Y99444D01*
G01X437513Y222001D02*
X271649Y114289D01*
G01X436681Y222833D02*
X271201Y115370D01*
G01D02*
X196266Y99444D01*
G01X271649Y114289D02*
X196714Y98363D01*
G01X436681Y222833D02*
X271201Y115370D01*
G01X437513Y222001D02*
X271649Y114289D01*
G01X262686Y511200D02*
X259725D01*
G01X262344Y512350D02*
X259763D01*
G01X327909Y553557D02*
X262686Y511200D01*
G01X327461Y554638D02*
X262344Y512350D01*
G01D02*
X259763D01*
G01X262686Y511200D02*
X259725D01*
G01X327461Y554638D02*
X262344Y512350D01*
G01X327909Y553557D02*
X262686Y511200D01*
G01X254832Y554147D02*
X203763Y520971D01*
G01X254384Y555228D02*
X203344Y522071D01*
G01X606840Y628968D02*
X254832Y554147D01*
G01X606393Y630049D02*
X254384Y555228D01*
G01D02*
X203344Y522071D01*
G01X254832Y554147D02*
X203763Y520971D01*
G01X606393Y630049D02*
X254384Y555228D01*
G01X606840Y628968D02*
X254832Y554147D01*
G01X266076Y963956D02*
X259725D01*
G01X266164Y965106D02*
X259763D01*
G01X504472Y927630D02*
X266076Y963956D01*
G01X504672Y928763D02*
X266164Y965106D01*
G01D02*
X259763D01*
G01X266076Y963956D02*
X259725D01*
G01X504672Y928763D02*
X266164Y965106D01*
G01X504472Y927630D02*
X266076Y963956D01*
G01X386762Y58444D02*
X383938D01*
G01X386641Y59594D02*
X383976D01*
G01X386641D02*
X383976D01*
G01X386762Y58444D02*
X383938D01*
G01X386751Y511200D02*
X383938D01*
G01X386630Y512350D02*
X383976D01*
G01X386630D02*
X383976D01*
G01X386751Y511200D02*
X383938D01*
G01X602940Y612015D02*
X327909Y553557D01*
G01X602492Y613096D02*
X327461Y554638D01*
G01X602492Y613096D02*
X327461Y554638D01*
G01X602940Y612015D02*
X327909Y553557D01*
G01X761514Y856045D02*
X318053Y918147D01*
G01X526079Y890177D02*
X318276Y919277D01*
G01X526079Y890177D02*
X318276Y919277D01*
G01X761514Y856045D02*
X318053Y918147D01*
G01X761514Y856045D02*
X318053Y918147D01*
G01X761514Y856045D02*
X318053Y918147D01*
G01X761514Y856045D02*
X318053Y918147D01*
G01X761514Y856045D02*
X318053Y918147D01*
G01X386539Y963956D02*
X383938D01*
G01X386628Y965106D02*
X383976D01*
G01X386628D02*
X383976D01*
G01X386539Y963956D02*
X383938D01*
G01X388397Y58791D02*
X386762Y58444D01*
G01X387949Y59872D02*
X386641Y59594D01*
G01X391049Y60514D02*
X388397Y58791D01*
G01X390217Y61345D02*
X387949Y59872D01*
G01X392017Y62006D02*
X391049Y60514D01*
G01X390936Y62453D02*
X390217Y61345D01*
G01X403464Y115853D02*
X392017Y62006D01*
G01X393608Y75024D02*
X390936Y62453D01*
G01X394482Y79132D02*
X394170Y77665D01*
G01X395355Y83240D02*
X395043Y81773D01*
G01X396228Y87349D02*
X395916Y85881D01*
G01X402383Y116301D02*
X396790Y89990D01*
G01X387949Y59872D02*
X386641Y59594D01*
G01X388397Y58791D02*
X386762Y58444D01*
G01X390217Y61345D02*
X387949Y59872D01*
G01X391049Y60514D02*
X388397Y58791D01*
G01X390936Y62453D02*
X390217Y61345D01*
G01X392017Y62006D02*
X391049Y60514D01*
G01X393608Y75024D02*
X390936Y62453D01*
G01X403464Y115853D02*
X392017Y62006D01*
G01X394482Y79132D02*
X394170Y77665D01*
G01X403464Y115853D02*
X392017Y62006D01*
G01X395355Y83240D02*
X395043Y81773D01*
G01X403464Y115853D02*
X392017Y62006D01*
G01X396228Y87349D02*
X395916Y85881D01*
G01X403464Y115853D02*
X392017Y62006D01*
G01X402383Y116301D02*
X396790Y89990D01*
G01X403464Y115853D02*
X392017Y62006D01*
G01X560660Y357916D02*
X403464Y115853D01*
G01X559828Y358748D02*
X402383Y116301D01*
G01X559828Y358748D02*
X402383Y116301D01*
G01X560660Y357916D02*
X403464Y115853D01*
G01X537075Y350075D02*
X406918Y149653D01*
G01X513969Y316609D02*
X406086Y150485D01*
G01X513969Y316609D02*
X406086Y150485D01*
G01X537075Y350075D02*
X406918Y149653D01*
G01X537075Y350075D02*
X406918Y149653D01*
G01X537075Y350075D02*
X406918Y149653D01*
G01X537075Y350075D02*
X406918Y149653D01*
G01X537075Y350075D02*
X406918Y149653D01*
G01X517245Y344776D02*
X437513Y222001D01*
G01X516413Y345608D02*
X436681Y222833D01*
G01X516413Y345608D02*
X436681Y222833D01*
G01X517245Y344776D02*
X437513Y222001D01*
G01X517881Y539040D02*
X386751Y511200D01*
G01X517434Y540121D02*
X386630Y512350D01*
G01X517434Y540121D02*
X386630Y512350D01*
G01X517881Y539040D02*
X386751Y511200D01*
G01X480769Y949414D02*
X386539Y963956D01*
G01X480972Y950547D02*
X386628Y965106D01*
G01X816505Y880883D02*
X480769Y949414D01*
G01X522728Y942024D02*
X480972Y950547D01*
G01D02*
X386628Y965106D01*
G01X480769Y949414D02*
X386539Y963956D01*
G01X522728Y942024D02*
X480972Y950547D01*
G01X816505Y880883D02*
X480769Y949414D01*
G01X816505Y880883D02*
X480769Y949414D01*
G01X816505Y880883D02*
X480769Y949414D01*
G01X816505Y880883D02*
X480769Y949414D01*
G01X816505Y880883D02*
X480769Y949414D01*
G01X510763Y58444D02*
X508150D01*
G01X510642Y59594D02*
X508188D01*
G01X511857Y58676D02*
X510763Y58444D01*
G01X511409Y59757D02*
X510642Y59594D01*
G01X514079Y60118D02*
X511857Y58676D01*
G01X513248Y60950D02*
X511409Y59757D01*
G01X520073Y69343D02*
X514079Y60118D01*
G01X518992Y69791D02*
X513248Y60950D01*
G01X563001Y271316D02*
X520073Y69343D01*
G01X561920Y271764D02*
X518992Y69791D01*
G01X510642Y59594D02*
X508188D01*
G01X510763Y58444D02*
X508150D01*
G01X511409Y59757D02*
X510642Y59594D01*
G01X511857Y58676D02*
X510763Y58444D01*
G01X513248Y60950D02*
X511409Y59757D01*
G01X514079Y60118D02*
X511857Y58676D01*
G01X518992Y69791D02*
X513248Y60950D01*
G01X520073Y69343D02*
X514079Y60118D01*
G01X561920Y271764D02*
X518992Y69791D01*
G01X563001Y271316D02*
X520073Y69343D01*
G01X653535Y410731D02*
X563001Y271316D01*
G01X572227Y287636D02*
X561920Y271764D01*
G01X572227Y287636D02*
X561920Y271764D01*
G01X653535Y410731D02*
X563001Y271316D01*
G01X653535Y410731D02*
X563001Y271316D01*
G01X653535Y410731D02*
X563001Y271316D01*
G01X653535Y410731D02*
X563001Y271316D01*
G01X653535Y410731D02*
X563001Y271316D01*
G01X574514Y291158D02*
X573697Y289900D01*
G01X576802Y294681D02*
X575985Y293423D01*
G01X574514Y291158D02*
X573697Y289900D01*
G01X576802Y294681D02*
X575985Y293423D01*
G01X981056Y630945D02*
X560660Y357916D01*
G01X980224Y631777D02*
X559828Y358748D01*
G01X980224Y631777D02*
X559828Y358748D01*
G01X981056Y630945D02*
X560660Y357916D01*
G01X516257Y320131D02*
X515440Y318873D01*
G01X518544Y323654D02*
X517727Y322396D01*
G01X520832Y327176D02*
X520015Y325918D01*
G01X536243Y350907D02*
X522302Y329440D01*
G01X976908Y635716D02*
X537075Y350075D01*
G01X976076Y636548D02*
X536243Y350907D01*
G01X516257Y320131D02*
X515440Y318873D01*
G01X518544Y323654D02*
X517727Y322396D01*
G01X520832Y327176D02*
X520015Y325918D01*
G01X536243Y350907D02*
X522302Y329440D01*
G01X976076Y636548D02*
X536243Y350907D01*
G01X976908Y635716D02*
X537075Y350075D01*
G01X970012Y638810D02*
X517245Y344776D01*
G01X969180Y639642D02*
X516413Y345608D01*
G01X969180Y639642D02*
X516413Y345608D01*
G01X970012Y638810D02*
X517245Y344776D01*
G01X511481Y511200D02*
X508150D01*
G01X511044Y512350D02*
X508188D01*
G01X564853Y558491D02*
X511481Y511200D01*
G01X564154Y559409D02*
X511044Y512350D01*
G01X947936Y807266D02*
X564853Y558491D01*
G01X628122Y600950D02*
X564154Y559409D01*
G01X511044Y512350D02*
X508188D01*
G01X511481Y511200D02*
X508150D01*
G01X564154Y559409D02*
X511044Y512350D01*
G01X564853Y558491D02*
X511481Y511200D01*
G01X628122Y600950D02*
X564154Y559409D01*
G01X947936Y807266D02*
X564853Y558491D01*
G01X947936Y807266D02*
X564853Y558491D01*
G01X947936Y807266D02*
X564853Y558491D01*
G01X947936Y807266D02*
X564853Y558491D01*
G01X947936Y807266D02*
X564853Y558491D01*
G01X944524Y816107D02*
X517881Y539040D01*
G01X720962Y672296D02*
X517434Y540121D01*
G01X720962Y672296D02*
X517434Y540121D01*
G01X944524Y816107D02*
X517881Y539040D01*
G01X944524Y816107D02*
X517881Y539040D01*
G01X944524Y816107D02*
X517881Y539040D01*
G01X944524Y816107D02*
X517881Y539040D01*
G01X944524Y816107D02*
X517881Y539040D01*
G01X526843Y941184D02*
X525373Y941484D01*
G01X530958Y940344D02*
X529489Y940644D01*
G01X535073Y939504D02*
X533604Y939804D01*
G01X816500Y882058D02*
X537719Y938964D01*
G01X526843Y941184D02*
X525373Y941484D01*
G01X530958Y940344D02*
X529489Y940644D01*
G01X535073Y939504D02*
X533604Y939804D01*
G01X816500Y882058D02*
X537719Y938964D01*
G01X794031Y869338D02*
X504472Y927630D01*
G01X794025Y870513D02*
X504672Y928763D01*
G01X794025Y870513D02*
X504672Y928763D01*
G01X794031Y869338D02*
X504472Y927630D01*
G01X530238Y889595D02*
X528752Y889803D01*
G01X534397Y889012D02*
X532912Y889220D01*
G01X538557Y888430D02*
X537071Y888638D01*
G01X761473Y857212D02*
X541231Y888055D01*
G01X530238Y889595D02*
X528752Y889803D01*
G01X534397Y889012D02*
X532912Y889220D01*
G01X538557Y888430D02*
X537071Y888638D01*
G01X761473Y857212D02*
X541231Y888055D01*
G01X511325Y963956D02*
X508150D01*
G01X511411Y965106D02*
X508188D01*
G01X511493Y965094D02*
X511411Y965106D01*
G01X511509Y965092D02*
X511493Y965094D01*
G01X511330Y963954D02*
X511325Y963955D01*
G01X524479Y963157D02*
X511509Y965092D01*
G01X511339Y963953D02*
X511330Y963954D01*
G01X524479Y963157D02*
X511509Y965092D01*
G01X621123Y947576D02*
X511339Y963953D01*
G01X511493Y965094D02*
X511411Y965106D01*
G01X511509Y965092D02*
X511493Y965094D01*
G01X524479Y963157D02*
X511509Y965092D01*
G01X528633Y962537D02*
X527149Y962759D01*
G01X532787Y961918D02*
X531303Y962139D01*
G01X536941Y961298D02*
X535457Y961519D01*
G01X621322Y948710D02*
X539611Y960900D01*
G01X511411Y965106D02*
X508188D01*
G01X511325Y963956D02*
X508150D01*
G01X511493Y965094D02*
X511411Y965106D01*
G01X511325Y963956D02*
X508150D01*
G01X621123Y947576D02*
X511339Y963953D01*
G01X511509Y965092D02*
X511493Y965094D01*
G01X511325Y963956D02*
X508150D01*
G01X621123Y947576D02*
X511339Y963953D01*
G01X524479Y963157D02*
X511509Y965092D01*
G01X511330Y963954D02*
X511325Y963955D01*
G01X511339Y963953D02*
X511330Y963954D01*
G01X621123Y947576D02*
X511339Y963953D01*
G01X528633Y962537D02*
X527149Y962759D01*
G01X621123Y947576D02*
X511339Y963953D01*
G01X532787Y961918D02*
X531303Y962139D01*
G01X621123Y947576D02*
X511339Y963953D01*
G01X536941Y961298D02*
X535457Y961519D01*
G01X621123Y947576D02*
X511339Y963953D01*
G01X621322Y948710D02*
X539611Y960900D01*
G01X621123Y947576D02*
X511339Y963953D01*
G01X635061Y58444D02*
X632363D01*
G01X634939Y59594D02*
X632401D01*
G01X635711Y58582D02*
X635061Y58444D01*
G01X634939Y59594D02*
X632401D01*
G01X635263Y59663D02*
X634939Y59594D01*
G01X638116Y60143D02*
X635711Y58582D01*
G01X637284Y60975D02*
X635263Y59663D01*
G01X640698Y64120D02*
X638116Y60143D01*
G01X639617Y64568D02*
X637284Y60975D01*
G01X710667Y393302D02*
X640698Y64120D01*
G01X641209Y72056D02*
X639617Y64568D01*
G01X642082Y76165D02*
X641770Y74697D01*
G01X642955Y80273D02*
X642643Y78806D01*
G01X643828Y84381D02*
X643517Y82914D01*
G01X709586Y393750D02*
X644390Y87022D01*
G01X634939Y59594D02*
X632401D01*
G01X635061Y58444D02*
X632363D01*
G01X635711Y58582D02*
X635061Y58444D01*
G01X635263Y59663D02*
X634939Y59594D01*
G01X635711Y58582D02*
X635061Y58444D01*
G01X637284Y60975D02*
X635263Y59663D01*
G01X638116Y60143D02*
X635711Y58582D01*
G01X639617Y64568D02*
X637284Y60975D01*
G01X640698Y64120D02*
X638116Y60143D01*
G01X641209Y72056D02*
X639617Y64568D01*
G01X710667Y393302D02*
X640698Y64120D01*
G01X642082Y76165D02*
X641770Y74697D01*
G01X710667Y393302D02*
X640698Y64120D01*
G01X642955Y80273D02*
X642643Y78806D01*
G01X710667Y393302D02*
X640698Y64120D01*
G01X643828Y84381D02*
X643517Y82914D01*
G01X710667Y393302D02*
X640698Y64120D01*
G01X709586Y393750D02*
X644390Y87022D01*
G01X710667Y393302D02*
X640698Y64120D01*
G01X579089Y298203D02*
X578272Y296945D01*
G01X652703Y411563D02*
X580560Y300467D01*
G01X579089Y298203D02*
X578272Y296945D01*
G01X652703Y411563D02*
X580560Y300467D01*
G01X988876Y628520D02*
X653535Y410731D01*
G01X988044Y629352D02*
X652703Y411563D01*
G01X988044Y629352D02*
X652703Y411563D01*
G01X988876Y628520D02*
X653535Y410731D01*
G01X633973Y511200D02*
X632363D01*
G01X633632Y512350D02*
X632401D01*
G01X635101Y511932D02*
X633973Y511200D01*
G01X633632Y512350D02*
X632401D01*
G01X634269Y512764D02*
X633632Y512350D01*
G01X724501Y649596D02*
X635101Y511932D01*
G01X657928Y549196D02*
X634269Y512764D01*
G01X660216Y552718D02*
X659399Y551460D01*
G01X662503Y556241D02*
X661686Y554983D01*
G01X664791Y559763D02*
X663974Y558505D01*
G01X723669Y650428D02*
X666262Y562028D01*
G01X633632Y512350D02*
X632401D01*
G01X633973Y511200D02*
X632363D01*
G01X635101Y511932D02*
X633973Y511200D01*
G01X634269Y512764D02*
X633632Y512350D01*
G01X635101Y511932D02*
X633973Y511200D01*
G01X657928Y549196D02*
X634269Y512764D01*
G01X724501Y649596D02*
X635101Y511932D01*
G01X660216Y552718D02*
X659399Y551460D01*
G01X724501Y649596D02*
X635101Y511932D01*
G01X662503Y556241D02*
X661686Y554983D01*
G01X724501Y649596D02*
X635101Y511932D01*
G01X664791Y559763D02*
X663974Y558505D01*
G01X724501Y649596D02*
X635101Y511932D01*
G01X723669Y650428D02*
X666262Y562028D01*
G01X724501Y649596D02*
X635101Y511932D01*
G01X631645Y603238D02*
X630387Y602421D01*
G01X702291Y649116D02*
X633909Y604709D01*
G01X631645Y603238D02*
X630387Y602421D01*
G01X702291Y649116D02*
X633909Y604709D01*
G01X930185Y824535D02*
X602940Y612015D01*
G01X612101Y619336D02*
X602492Y613096D01*
G01X615623Y621624D02*
X614365Y620807D01*
G01X619146Y623911D02*
X617888Y623094D01*
G01X622668Y626199D02*
X621410Y625382D01*
G01X929737Y825616D02*
X624932Y627669D01*
G01X612101Y619336D02*
X602492Y613096D01*
G01X930185Y824535D02*
X602940Y612015D01*
G01X615623Y621624D02*
X614365Y620807D01*
G01X930185Y824535D02*
X602940Y612015D01*
G01X619146Y623911D02*
X617888Y623094D01*
G01X930185Y824535D02*
X602940Y612015D01*
G01X622668Y626199D02*
X621410Y625382D01*
G01X930185Y824535D02*
X602940Y612015D01*
G01X929737Y825616D02*
X624932Y627669D01*
G01X930185Y824535D02*
X602940Y612015D01*
G01X911895Y826996D02*
X606840Y628968D01*
G01X754312Y726072D02*
X606393Y630049D01*
G01X754312Y726072D02*
X606393Y630049D01*
G01X911895Y826996D02*
X606840Y628968D01*
G01X911895Y826996D02*
X606840Y628968D01*
G01X911895Y826996D02*
X606840Y628968D01*
G01X911895Y826996D02*
X606840Y628968D01*
G01X911895Y826996D02*
X606840Y628968D01*
G01X866398Y897875D02*
X621123Y947576D01*
G01X866408Y899047D02*
X621322Y948710D01*
G01X866408Y899047D02*
X621322Y948710D01*
G01X866398Y897875D02*
X621123Y947576D01*
G01X637530Y963956D02*
X632363D01*
G01X637609Y965106D02*
X632401D01*
G01X719321Y952763D02*
X637530Y963956D01*
G01X719519Y953897D02*
X637609Y965106D01*
G01D02*
X632401D01*
G01X637530Y963956D02*
X632363D01*
G01X719519Y953897D02*
X637609Y965106D01*
G01X719321Y952763D02*
X637530Y963956D01*
G01X758853Y58444D02*
X756576D01*
G01X758511Y59594D02*
X756614D01*
G01X760127Y59273D02*
X758853Y58444D01*
G01X759295Y60105D02*
X758511Y59594D01*
G01X760870Y60416D02*
X760127Y59273D01*
G01X759789Y60864D02*
X759295Y60105D01*
G01X762181Y66581D02*
X760870Y60416D01*
G01X761005Y66581D02*
X759789Y60864D01*
G01X741643Y163204D02*
X762181Y66581D01*
G01X750787Y114653D02*
X761005Y66581D01*
G01X758511Y59594D02*
X756614D01*
G01X758853Y58444D02*
X756576D01*
G01X759295Y60105D02*
X758511Y59594D01*
G01X760127Y59273D02*
X758853Y58444D01*
G01X759789Y60864D02*
X759295Y60105D01*
G01X760870Y60416D02*
X760127Y59273D01*
G01X761005Y66581D02*
X759789Y60864D01*
G01X762181Y66581D02*
X760870Y60416D01*
G01X750787Y114653D02*
X761005Y66581D01*
G01X741643Y163204D02*
X762181Y66581D01*
G01X741643Y163204D02*
X762181Y66581D01*
G01X740467Y163204D02*
X750787Y114653D01*
G01X784565Y365142D02*
X741643Y163204D01*
G01X751097Y213220D02*
X740467Y163204D01*
G01D02*
X750787Y114653D01*
G01X751097Y213220D02*
X740467Y163204D01*
G01X784565Y365142D02*
X741643Y163204D01*
G01X784565Y365142D02*
X741643Y163204D01*
G01X784565Y365142D02*
X741643Y163204D01*
G01X784565Y365142D02*
X741643Y163204D01*
G01X784565Y365142D02*
X741643Y163204D01*
G01X751971Y217328D02*
X751659Y215861D01*
G01X752844Y221436D02*
X752532Y219969D01*
G01X753717Y225545D02*
X753405Y224077D01*
G01X783389Y365142D02*
X754278Y228186D01*
G01X751971Y217328D02*
X751659Y215861D01*
G01X752844Y221436D02*
X752532Y219969D01*
G01X753717Y225545D02*
X753405Y224077D01*
G01X783389Y365142D02*
X754278Y228186D01*
G01X763782Y475102D02*
X710667Y393302D01*
G01X762950Y475934D02*
X709586Y393750D01*
G01X762950Y475934D02*
X709586Y393750D01*
G01X763782Y475102D02*
X710667Y393302D01*
G01X759263Y511200D02*
X756576D01*
G01X759141Y512350D02*
X756614D01*
G01X760234Y511406D02*
X759263Y511200D01*
G01X759786Y512487D02*
X759141Y512350D01*
G01X761621Y512308D02*
X760234Y511406D01*
G01X760789Y513139D02*
X759786Y512487D01*
G01X763175Y514702D02*
X761621Y512308D01*
G01X762094Y515149D02*
X760789Y513139D01*
G01X772832Y560353D02*
X763175Y514702D01*
G01X771751Y560800D02*
X762094Y515149D01*
G01X759141Y512350D02*
X756614D01*
G01X759263Y511200D02*
X756576D01*
G01X759786Y512487D02*
X759141Y512350D01*
G01X760234Y511406D02*
X759263Y511200D01*
G01X760789Y513139D02*
X759786Y512487D01*
G01X761621Y512308D02*
X760234Y511406D01*
G01X762094Y515149D02*
X760789Y513139D01*
G01X763175Y514702D02*
X761621Y512308D01*
G01X771751Y560800D02*
X762094Y515149D01*
G01X772832Y560353D02*
X763175Y514702D01*
G01X993930Y624587D02*
X763782Y475102D01*
G01X993098Y625419D02*
X762950Y475934D01*
G01X993098Y625419D02*
X762950Y475934D01*
G01X993930Y624587D02*
X763782Y475102D01*
G01X953932Y798591D02*
X724501Y649596D01*
G01X953484Y799672D02*
X723669Y650428D01*
G01X953484Y799672D02*
X723669Y650428D01*
G01X953932Y798591D02*
X724501Y649596D01*
G01X705881Y651447D02*
X704623Y650630D01*
G01X947488Y808347D02*
X708212Y652961D01*
G01X705881Y651447D02*
X704623Y650630D01*
G01X947488Y808347D02*
X708212Y652961D01*
G01X724485Y674583D02*
X723227Y673766D01*
G01X728007Y676870D02*
X726749Y676054D01*
G01X731529Y679158D02*
X730271Y678341D01*
G01X944076Y817188D02*
X733794Y680628D01*
G01X724485Y674583D02*
X723227Y673766D01*
G01X728007Y676870D02*
X726749Y676054D01*
G01X731529Y679158D02*
X730271Y678341D01*
G01X944076Y817188D02*
X733794Y680628D01*
G01X757835Y728359D02*
X756577Y727542D01*
G01X761358Y730646D02*
X760100Y729829D01*
G01X764881Y732933D02*
X763622Y732116D01*
G01X911448Y828077D02*
X767145Y734403D01*
G01X757835Y728359D02*
X756577Y727542D01*
G01X761358Y730646D02*
X760100Y729829D01*
G01X764881Y732933D02*
X763622Y732116D01*
G01X911448Y828077D02*
X767145Y734403D01*
G01X1018812Y910736D02*
X761514Y856045D01*
G01X1018812Y910736D02*
X761514Y856045D01*
G01X907759Y912713D02*
X719321Y952763D01*
G01X849655Y926238D02*
X719519Y953897D01*
G01X849655Y926238D02*
X719519Y953897D01*
G01X907759Y912713D02*
X719321Y952763D01*
G01X907759Y912713D02*
X719321Y952763D01*
G01X907759Y912713D02*
X719321Y952763D01*
G01X907759Y912713D02*
X719321Y952763D01*
G01X907759Y912713D02*
X719321Y952763D01*
G01X1018812Y911912D02*
X761473Y857212D01*
G01X1018812Y911912D02*
X761473Y857212D01*
G01X759696Y963956D02*
X756576D01*
G01X759822Y965106D02*
X756614D01*
G01X843651Y945437D02*
X759696Y963956D01*
G01X843851Y946571D02*
X759822Y965106D01*
G01D02*
X756614D01*
G01X759696Y963956D02*
X756576D01*
G01X843851Y946571D02*
X759822Y965106D01*
G01X843651Y945437D02*
X759696Y963956D01*
G01X772579Y421536D02*
X784565Y365142D01*
G01X771403Y421536D02*
X783389Y365142D01*
G01X771403Y421536D02*
X783389Y365142D01*
G01X772579Y421536D02*
X784565Y365142D01*
G01X782365Y467575D02*
X772579Y421536D01*
G01X781284Y468023D02*
X771403Y421536D01*
G01X796267Y488984D02*
X782365Y467575D01*
G01X795435Y489816D02*
X781284Y468023D01*
G01D02*
X771403Y421536D01*
G01X782365Y467575D02*
X772579Y421536D01*
G01X795435Y489816D02*
X781284Y468023D01*
G01X796267Y488984D02*
X782365Y467575D01*
G01X829393Y647449D02*
X772832Y560353D01*
G01X816634Y629914D02*
X771751Y560800D01*
G01X816634Y629914D02*
X771751Y560800D01*
G01X829393Y647449D02*
X772832Y560353D01*
G01X829393Y647449D02*
X772832Y560353D01*
G01X829393Y647449D02*
X772832Y560353D01*
G01X829393Y647449D02*
X772832Y560353D01*
G01X829393Y647449D02*
X772832Y560353D01*
G01X998814Y620522D02*
X796267Y488984D01*
G01X997982Y621354D02*
X795435Y489816D01*
G01X997982Y621354D02*
X795435Y489816D01*
G01X998814Y620522D02*
X796267Y488984D01*
G01X818921Y633436D02*
X818104Y632178D01*
G01X821209Y636959D02*
X820392Y635701D01*
G01X823540Y640549D02*
X822723Y639291D01*
G01X828494Y648177D02*
X825054Y642880D01*
G01X901726Y719782D02*
X829393Y647449D01*
G01X900998Y720681D02*
X828494Y648177D01*
G01X818921Y633436D02*
X818104Y632178D01*
G01X821209Y636959D02*
X820392Y635701D01*
G01X823540Y640549D02*
X822723Y639291D01*
G01X828494Y648177D02*
X825054Y642880D01*
G01X900998Y720681D02*
X828494Y648177D01*
G01X901726Y719782D02*
X829393Y647449D01*
G01X901756Y937759D02*
X843651Y945437D01*
G01X865343Y943731D02*
X843851Y946571D01*
G01X865343Y943731D02*
X843851Y946571D01*
G01X901756Y937759D02*
X843651Y945437D01*
G01X901756Y937759D02*
X843651Y945437D01*
G01X901756Y937759D02*
X843651Y945437D01*
G01X901756Y937759D02*
X843651Y945437D01*
G01X853763Y925365D02*
X852296Y925677D01*
G01X857871Y924492D02*
X856404Y924804D01*
G01X861979Y923619D02*
X860512Y923931D01*
G01X853763Y925365D02*
X852296Y925677D01*
G01X857871Y924492D02*
X856404Y924804D01*
G01X861979Y923619D02*
X860512Y923931D01*
G01X1018419Y923800D02*
X816505Y880883D01*
G01X1018419Y924976D02*
X816500Y882058D01*
G01X1018419Y924976D02*
X816500Y882058D01*
G01X1018419Y923800D02*
X816505Y880883D01*
G01X1019118Y917181D02*
X794031Y869338D01*
G01X796475Y871034D02*
X794025Y870513D01*
G01X800583Y871907D02*
X799116Y871595D01*
G01X804692Y872780D02*
X803224Y872468D01*
G01X808800Y873653D02*
X807333Y873342D01*
G01X1019118Y918357D02*
X811441Y874215D01*
G01X796475Y871034D02*
X794025Y870513D01*
G01X1019118Y917181D02*
X794031Y869338D01*
G01X800583Y871907D02*
X799116Y871595D01*
G01X1019118Y917181D02*
X794031Y869338D01*
G01X804692Y872780D02*
X803224Y872468D01*
G01X1019118Y917181D02*
X794031Y869338D01*
G01X808800Y873653D02*
X807333Y873342D01*
G01X1019118Y917181D02*
X794031Y869338D01*
G01X1019118Y918357D02*
X811441Y874215D01*
G01X1019118Y917181D02*
X794031Y869338D01*
G01X1031855Y804289D02*
X901726Y719782D01*
G01X1031407Y805370D02*
X900998Y720681D01*
G01X1031407Y805370D02*
X900998Y720681D01*
G01X1031855Y804289D02*
X901726Y719782D01*
G01X1065184Y822238D02*
X953932Y798591D01*
G01X1065063Y823388D02*
X953484Y799672D01*
G01X1065063Y823388D02*
X953484Y799672D01*
G01X1065184Y822238D02*
X953932Y798591D01*
G01X1071791Y833587D02*
X947936Y807266D01*
G01X1071791Y834763D02*
X947488Y808347D01*
G01X1071791Y834763D02*
X947488Y808347D01*
G01X1071791Y833587D02*
X947936Y807266D01*
G01X1064067Y841513D02*
X944524Y816107D01*
G01X1064067Y842689D02*
X944076Y817188D01*
G01X1064067Y842689D02*
X944076Y817188D01*
G01X1064067Y841513D02*
X944524Y816107D01*
G01X1052118Y850453D02*
X930185Y824535D01*
G01X1052118Y851629D02*
X929737Y825616D01*
G01X1052118Y851629D02*
X929737Y825616D01*
G01X1052118Y850453D02*
X930185Y824535D01*
G01X1052366Y856856D02*
X911895Y826996D01*
G01X1052366Y858032D02*
X911448Y828077D01*
G01X1052366Y858032D02*
X911448Y828077D01*
G01X1052366Y856856D02*
X911895Y826996D01*
G01X869507Y943181D02*
X868020Y943378D01*
G01X873671Y942631D02*
X872184Y942827D01*
G01X877834Y942081D02*
X876347Y942277D01*
G01X960007Y930063D02*
X901756Y937759D01*
G01X959961Y931230D02*
X880511Y941727D01*
G01X869507Y943181D02*
X868020Y943378D01*
G01X873671Y942631D02*
X872184Y942827D01*
G01X877834Y942081D02*
X876347Y942277D01*
G01X959961Y931230D02*
X880511Y941727D01*
G01X960007Y930063D02*
X901756Y937759D01*
G01X907759Y913889D02*
X864620Y923058D01*
G01X1018529Y936258D02*
X907759Y912713D01*
G01X1018529Y937434D02*
X907759Y913889D01*
G01D02*
X864620Y923058D01*
G01X1018529Y937434D02*
X907759Y913889D01*
G01X1018529Y936258D02*
X907759Y912713D01*
G01X872955Y899084D02*
X866398Y897875D01*
G01X872731Y900213D02*
X866408Y899047D01*
G01X1018382Y929994D02*
X872955Y899084D01*
G01X1018382Y931170D02*
X872731Y900213D01*
G01D02*
X866408Y899047D01*
G01X872955Y899084D02*
X866398Y897875D01*
G01X1018382Y931170D02*
X872731Y900213D01*
G01X1018382Y929994D02*
X872955Y899084D01*
G01X1058051Y711739D02*
X998814Y620522D01*
G01X1057219Y712571D02*
X997982Y621354D01*
G01X1057219Y712571D02*
X997982Y621354D01*
G01X1058051Y711739D02*
X998814Y620522D01*
G01X1054332Y717594D02*
X993930Y624587D01*
G01X1053500Y718426D02*
X993098Y625419D01*
G01X1053500Y718426D02*
X993098Y625419D01*
G01X1054332Y717594D02*
X993930Y624587D01*
G01X1050352Y723183D02*
X988876Y628520D01*
G01X1049520Y724015D02*
X988044Y629352D01*
G01X1049520Y724015D02*
X988044Y629352D01*
G01X1050352Y723183D02*
X988876Y628520D01*
G01X1043107Y726492D02*
X981056Y630945D01*
G01X1042275Y727324D02*
X980224Y631777D01*
G01X1042275Y727324D02*
X980224Y631777D01*
G01X1043107Y726492D02*
X981056Y630945D01*
G01X1038771Y730974D02*
X976908Y635716D01*
G01X1037939Y731806D02*
X976076Y636548D01*
G01X1037939Y731806D02*
X976076Y636548D01*
G01X1038771Y730974D02*
X976908Y635716D01*
G01X1031719Y733827D02*
X970012Y638810D01*
G01X1030887Y734659D02*
X969180Y639642D01*
G01X1030887Y734659D02*
X969180Y639642D01*
G01X1031719Y733827D02*
X970012Y638810D01*
G01X1081750Y736771D02*
X1053500Y718426D01*
G01X1081750Y736771D02*
X1053500Y718426D01*
G01X1079705Y742245D02*
X1050352Y723183D01*
G01X1079257Y743326D02*
X1049520Y724015D01*
G01X1079257Y743326D02*
X1049520Y724015D01*
G01X1079705Y742245D02*
X1050352Y723183D01*
G01X1077584Y748882D02*
X1043107Y726492D01*
G01X1077136Y749963D02*
X1042275Y727324D01*
G01X1077136Y749963D02*
X1042275Y727324D01*
G01X1077584Y748882D02*
X1043107Y726492D01*
G01X1077100Y755866D02*
X1038771Y730974D01*
G01X1076652Y756947D02*
X1037939Y731806D01*
G01X1076652Y756947D02*
X1037939Y731806D01*
G01X1077100Y755866D02*
X1038771Y730974D01*
G01X1076306Y762783D02*
X1031719Y733827D01*
G01X1075858Y763864D02*
X1030887Y734659D01*
G01X1075858Y763864D02*
X1030887Y734659D01*
G01X1076306Y762783D02*
X1031719Y733827D01*
G01X1082964Y815152D02*
X1031855Y804289D01*
G01X1082843Y816302D02*
X1031407Y805370D01*
G01X1082843Y816302D02*
X1031407Y805370D01*
G01X1082964Y815152D02*
X1031855Y804289D01*
G01X1084835Y843498D02*
X1052118Y850453D01*
G01X1084956Y844648D02*
X1052118Y851629D01*
G01X1084956Y844648D02*
X1052118Y851629D01*
G01X1084835Y843498D02*
X1052118Y850453D01*
G01X1018756Y942552D02*
X960007Y930063D01*
G01X1018756Y943728D02*
X959961Y931230D01*
G01X1051348Y935624D02*
X1018756Y942552D01*
G01X1035291Y940214D02*
X1018756Y943728D01*
G01X1051469Y936774D02*
X1035291Y940213D01*
G01X1100112Y935624D02*
X1051348D01*
G01X1100112Y936774D02*
X1051469D01*
G01X1018756Y943728D02*
X959961Y931230D01*
G01X1018756Y942552D02*
X960007Y930063D01*
G01X1035291Y940214D02*
X1018756Y943728D01*
G01X1051348Y935624D02*
X1018756Y942552D01*
G01X1051469Y936774D02*
X1035291Y940213D01*
G01X1051348Y935624D02*
X1018756Y942552D01*
G01X1100112Y936774D02*
X1051469D01*
G01X1100112Y935624D02*
X1051348D01*
G01X1054857Y928537D02*
X1018529Y936258D01*
G01X1054978Y929687D02*
X1018529Y937434D01*
G01X1054978Y929687D02*
X1018529Y937434D01*
G01X1054857Y928537D02*
X1018529Y936258D01*
G01X1058581Y921451D02*
X1018382Y929994D01*
G01X1058702Y922601D02*
X1018382Y931170D01*
G01X1058702Y922601D02*
X1018382Y931170D01*
G01X1058581Y921451D02*
X1018382Y929994D01*
G01X1062822Y914364D02*
X1018419Y923800D01*
G01X1062943Y915514D02*
X1018419Y924976D01*
G01X1062943Y915514D02*
X1018419Y924976D01*
G01X1062822Y914364D02*
X1018419Y923800D01*
G01X1065724Y907278D02*
X1019118Y917181D01*
G01X1065845Y908428D02*
X1019118Y918357D01*
G01X1065845Y908428D02*
X1019118Y918357D01*
G01X1065724Y907278D02*
X1019118Y917181D01*
G01X1068479Y900191D02*
X1018812Y910736D01*
G01X1068600Y901341D02*
X1018812Y911912D01*
G01X1068600Y901341D02*
X1018812Y911912D01*
G01X1068479Y900191D02*
X1018812Y910736D01*
G01X1081870Y850585D02*
X1052366Y856856D01*
G01X1081991Y851735D02*
X1052366Y858032D01*
G01X1081991Y851735D02*
X1052366Y858032D01*
G01X1081870Y850585D02*
X1052366Y856856D01*
G01X1135888Y724176D02*
X1160397Y718966D01*
G01X1135767Y723026D02*
X1159949Y717885D01*
G01X1103812Y724176D02*
X1135888D01*
G01X1103812Y723026D02*
X1135767D01*
G01X1102688Y725300D02*
G03X1103812Y724176I1124J0D01*
G01X1101538Y725300D02*
G03X1103812Y723026I2274J0D01*
G01X1102688Y726400D02*
Y725300D01*
G01X1101538Y726400D02*
Y725300D01*
G01X1135767Y723026D02*
X1159949Y717885D01*
G01X1135888Y724176D02*
X1160397Y718966D01*
G01X1103812Y723026D02*
X1135767D01*
G01X1103812Y724176D02*
X1135888D01*
G01X1101538Y725300D02*
G03X1103812Y723026I2274J0D01*
G01X1102688Y725300D02*
G03X1103812Y724176I1124J0D01*
G01X1101538Y726400D02*
Y725300D01*
G01X1102688Y726400D02*
Y725300D01*
G01X1135724Y717089D02*
X1150590Y714452D01*
G01X1135622Y715939D02*
X1150159Y713360D01*
G01X1099875Y717089D02*
X1135724D01*
G01X1099875Y715939D02*
X1135622D01*
G01X1098751Y718213D02*
G03X1099875Y717089I1124J0D01*
G01X1097601Y718213D02*
G03X1099875Y715939I2274J0D01*
G01X1098751Y719313D02*
Y718213D01*
G01X1097601Y719313D02*
Y718213D01*
G01X1135622Y715939D02*
X1150159Y713360D01*
G01X1135724Y717089D02*
X1150590Y714452D01*
G01X1099875Y715939D02*
X1135622D01*
G01X1099875Y717089D02*
X1135724D01*
G01X1097601Y718213D02*
G03X1099875Y715939I2274J0D01*
G01X1098751Y718213D02*
G03X1099875Y717089I1124J0D01*
G01X1097601Y719313D02*
Y718213D01*
G01X1098751Y719313D02*
Y718213D01*
G01X1136321Y710002D02*
X1151063Y706869D01*
G01X1136200Y708852D02*
X1150615Y705788D01*
G01X1103812Y710002D02*
X1136321D01*
G01X1103812Y708852D02*
X1136200D01*
G01X1102688Y711126D02*
G03X1103812Y710002I1124J0D01*
G01X1101538Y711126D02*
G03X1103812Y708852I2274J0D01*
G01X1102688Y712226D02*
Y711126D01*
G01X1101538Y712226D02*
Y711126D01*
G01X1136200Y708852D02*
X1150615Y705788D01*
G01X1136321Y710002D02*
X1151063Y706869D01*
G01X1103812Y708852D02*
X1136200D01*
G01X1103812Y710002D02*
X1136321D01*
G01X1101538Y711126D02*
G03X1103812Y708852I2274J0D01*
G01X1102688Y711126D02*
G03X1103812Y710002I1124J0D01*
G01X1101538Y712226D02*
Y711126D01*
G01X1102688Y712226D02*
Y711126D01*
G01X1148775Y699152D02*
X1159102Y692446D01*
G01X1136683Y702916D02*
X1149224Y700233D01*
G01X1136561Y701766D02*
X1148775Y699152D01*
G01X1099875Y702916D02*
X1136683D01*
G01X1099875Y701766D02*
X1136561D01*
G01X1098751Y704040D02*
G03X1099875Y702916I1124J0D01*
G01X1097601Y704040D02*
G03X1099875Y701766I2274J0D01*
G01X1098751Y705140D02*
Y704040D01*
G01X1097601Y705140D02*
Y704040D01*
G01X1148775Y699152D02*
X1159102Y692446D01*
G01X1136561Y701766D02*
X1148775Y699152D01*
G01X1136683Y702916D02*
X1149224Y700233D01*
G01X1099875Y701766D02*
X1136561D01*
G01X1099875Y702916D02*
X1136683D01*
G01X1097601Y704040D02*
G03X1099875Y701766I2274J0D01*
G01X1098751Y704040D02*
G03X1099875Y702916I1124J0D01*
G01X1097601Y705140D02*
Y704040D01*
G01X1098751Y705140D02*
Y704040D01*
G01X1145559Y693719D02*
X1154519Y687910D01*
G01X1145112Y692638D02*
X1153688Y687078D01*
G01X1135629Y695829D02*
X1145559Y693719D01*
G01X1135508Y694679D02*
X1145112Y692638D01*
G01X1103812Y695829D02*
X1135629D01*
G01X1103812Y694679D02*
X1135508D01*
G01X1102688Y696953D02*
G03X1103812Y695829I1124J0D01*
G01X1101538Y696953D02*
G03X1103812Y694679I2274J0D01*
G01X1102688Y698053D02*
Y696953D01*
G01X1101538Y698053D02*
Y696953D01*
G01X1145112Y692638D02*
X1153688Y687078D01*
G01X1145559Y693719D02*
X1154519Y687910D01*
G01X1135508Y694679D02*
X1145112Y692638D01*
G01X1135629Y695829D02*
X1145559Y693719D01*
G01X1103812Y694679D02*
X1135508D01*
G01X1103812Y695829D02*
X1135629D01*
G01X1101538Y696953D02*
G03X1103812Y694679I2274J0D01*
G01X1102688Y696953D02*
G03X1103812Y695829I1124J0D01*
G01X1101538Y698053D02*
Y696953D01*
G01X1102688Y698053D02*
Y696953D01*
G01X1147636Y683857D02*
X1183110Y629231D01*
G01X1146804Y683025D02*
X1182029Y628784D01*
G01X1143058Y686831D02*
X1147636Y683857D01*
G01X1142610Y685750D02*
X1146804Y683025D01*
G01X1134057Y688743D02*
X1143058Y686831D01*
G01X1133936Y687593D02*
X1142610Y685750D01*
G01X1099875Y688743D02*
X1134057D01*
G01X1099875Y687593D02*
X1133936D01*
G01X1098751Y689867D02*
G03X1099875Y688743I1124J0D01*
G01X1097601Y689867D02*
G03X1099875Y687593I2274J0D01*
G01X1098751Y690967D02*
Y689867D01*
G01X1097601Y690967D02*
Y689867D01*
G01X1146804Y683025D02*
X1182029Y628784D01*
G01X1147636Y683857D02*
X1183110Y629231D01*
G01X1142610Y685750D02*
X1146804Y683025D01*
G01X1143058Y686831D02*
X1147636Y683857D01*
G01X1133936Y687593D02*
X1142610Y685750D01*
G01X1134057Y688743D02*
X1143058Y686831D01*
G01X1099875Y687593D02*
X1133936D01*
G01X1099875Y688743D02*
X1134057D01*
G01X1097601Y689867D02*
G03X1099875Y687593I2274J0D01*
G01X1098751Y689867D02*
G03X1099875Y688743I1124J0D01*
G01X1097601Y690967D02*
Y689867D01*
G01X1098751Y690967D02*
Y689867D01*
G01X1085294Y729430D02*
X1058051Y711739D01*
G01X1084846Y730511D02*
X1057219Y712571D01*
G01X1088500Y730112D02*
X1085294Y729430D01*
G01X1088379Y731262D02*
X1084846Y730511D01*
G01X1096175Y730112D02*
X1088500D01*
G01X1096175Y731262D02*
X1088379D01*
G01X1098751Y732688D02*
G02X1096175Y730112I-2576J0D01*
G01X1097601Y732688D02*
G02X1096175Y731262I-1426J0D01*
G01X1098751Y733388D02*
Y732688D01*
G01X1097601Y733388D02*
Y732688D01*
G01X1084846Y730511D02*
X1057219Y712571D01*
G01X1085294Y729430D02*
X1058051Y711739D01*
G01X1088379Y731262D02*
X1084846Y730511D01*
G01X1088500Y730112D02*
X1085294Y729430D01*
G01X1096175Y731262D02*
X1088379D01*
G01X1096175Y730112D02*
X1088500D01*
G01X1097601Y732688D02*
G02X1096175Y731262I-1426J0D01*
G01X1098751Y732688D02*
G02X1096175Y730112I-2576J0D01*
G01X1097601Y733388D02*
Y732688D01*
G01X1098751Y733388D02*
Y732688D01*
G01X1082198Y735690D02*
X1054332Y717594D01*
G01X1089300Y737199D02*
X1082198Y735690D01*
G01X1089179Y738349D02*
X1081750Y736771D01*
G01X1100112Y737199D02*
X1089300D01*
G01X1100112Y738349D02*
X1089179D01*
G01X1102688Y739775D02*
G02X1100112Y737199I-2576J0D01*
G01X1101538Y739775D02*
G02X1100112Y738349I-1426J0D01*
G01X1102688Y740475D02*
Y739775D01*
G01X1101538Y740475D02*
Y739775D01*
G01X1082198Y735690D02*
X1054332Y717594D01*
G01X1089179Y738349D02*
X1081750Y736771D01*
G01X1089300Y737199D02*
X1082198Y735690D01*
G01X1100112Y738349D02*
X1089179D01*
G01X1100112Y737199D02*
X1089300D01*
G01X1101538Y739775D02*
G02X1100112Y738349I-1426J0D01*
G01X1102688Y739775D02*
G02X1100112Y737199I-2576J0D01*
G01X1101538Y740475D02*
Y739775D01*
G01X1102688Y740475D02*
Y739775D01*
G01X1089300Y744285D02*
X1079705Y742245D01*
G01X1089179Y745435D02*
X1079257Y743326D01*
G01X1096175Y744285D02*
X1089300D01*
G01X1096175Y745435D02*
X1089179D01*
G01X1098751Y746861D02*
G02X1096175Y744285I-2576J0D01*
G01X1097601Y746861D02*
G02X1096175Y745435I-1426J0D01*
G01X1098751Y747561D02*
Y746861D01*
G01X1097601Y747561D02*
Y746861D01*
G01X1089179Y745435D02*
X1079257Y743326D01*
G01X1089300Y744285D02*
X1079705Y742245D01*
G01X1096175Y745435D02*
X1089179D01*
G01X1096175Y744285D02*
X1089300D01*
G01X1097601Y746861D02*
G02X1096175Y745435I-1426J0D01*
G01X1098751Y746861D02*
G02X1096175Y744285I-2576J0D01*
G01X1097601Y747561D02*
Y746861D01*
G01X1098751Y747561D02*
Y746861D01*
G01X1089300Y751372D02*
X1077584Y748882D01*
G01X1089179Y752522D02*
X1077136Y749963D01*
G01X1100112Y751372D02*
X1089300D01*
G01X1100112Y752522D02*
X1089179D01*
G01X1102688Y753948D02*
G02X1100112Y751372I-2576J0D01*
G01X1101538Y753948D02*
G02X1100112Y752522I-1426J0D01*
G01X1102688Y754648D02*
Y753948D01*
G01X1101538Y754648D02*
Y753948D01*
G01X1089179Y752522D02*
X1077136Y749963D01*
G01X1089300Y751372D02*
X1077584Y748882D01*
G01X1100112Y752522D02*
X1089179D01*
G01X1100112Y751372D02*
X1089300D01*
G01X1101538Y753948D02*
G02X1100112Y752522I-1426J0D01*
G01X1102688Y753948D02*
G02X1100112Y751372I-2576J0D01*
G01X1101538Y754648D02*
Y753948D01*
G01X1102688Y754648D02*
Y753948D01*
G01X1089300Y758459D02*
X1077100Y755866D01*
G01X1089179Y759609D02*
X1076652Y756947D01*
G01X1096175Y758459D02*
X1089300D01*
G01X1096175Y759609D02*
X1089179D01*
G01X1098751Y761035D02*
G02X1096175Y758459I-2576J0D01*
G01X1097601Y761035D02*
G02X1096175Y759609I-1426J0D01*
G01X1098751Y761735D02*
Y761035D01*
G01X1097601Y761735D02*
Y761035D01*
G01X1089179Y759609D02*
X1076652Y756947D01*
G01X1089300Y758459D02*
X1077100Y755866D01*
G01X1096175Y759609D02*
X1089179D01*
G01X1096175Y758459D02*
X1089300D01*
G01X1097601Y761035D02*
G02X1096175Y759609I-1426J0D01*
G01X1098751Y761035D02*
G02X1096175Y758459I-2576J0D01*
G01X1097601Y761735D02*
Y761035D01*
G01X1098751Y761735D02*
Y761035D01*
G01X1103573Y809215D02*
X1186469D01*
G01X1103573Y808065D02*
X1186348D01*
G01X1102688Y810100D02*
G03X1103573Y809215I885J0D01*
G01X1101538Y810100D02*
G03X1103573Y808065I2035J0D01*
G01X1102688Y811600D02*
Y810100D01*
G01X1101538Y811600D02*
Y810100D01*
G01X1103573Y808065D02*
X1186348D01*
G01X1103573Y809215D02*
X1186469D01*
G01X1101538Y810100D02*
G03X1103573Y808065I2035J0D01*
G01X1102688Y810100D02*
G03X1103573Y809215I885J0D01*
G01X1101538Y811600D02*
Y810100D01*
G01X1102688Y811600D02*
Y810100D01*
G01X1099636Y802128D02*
X1189361D01*
G01X1099636Y800978D02*
X1189240D01*
G01X1098751Y803013D02*
G03X1099636Y802128I885J0D01*
G01X1097601Y803013D02*
G03X1099636Y800978I2035J0D01*
G01X1098751Y804513D02*
Y803013D01*
G01X1097601Y804513D02*
Y803013D01*
G01X1099636Y800978D02*
X1189240D01*
G01X1099636Y802128D02*
X1189361D01*
G01X1097601Y803013D02*
G03X1099636Y800978I2035J0D01*
G01X1098751Y803013D02*
G03X1099636Y802128I885J0D01*
G01X1097601Y804513D02*
Y803013D01*
G01X1098751Y804513D02*
Y803013D01*
G01X1103573Y795042D02*
X1193494D01*
G01X1103573Y793892D02*
X1193373D01*
G01X1102688Y795927D02*
G03X1103573Y795042I885J0D01*
G01X1101538Y795927D02*
G03X1103573Y793892I2035J0D01*
G01X1102688Y797427D02*
Y795927D01*
G01X1101538Y797427D02*
Y795927D01*
G01X1103573Y793892D02*
X1193373D01*
G01X1103573Y795042D02*
X1193494D01*
G01X1101538Y795927D02*
G03X1103573Y793892I2035J0D01*
G01X1102688Y795927D02*
G03X1103573Y795042I885J0D01*
G01X1101538Y797427D02*
Y795927D01*
G01X1102688Y797427D02*
Y795927D01*
G01X1099636Y787955D02*
X1168782D01*
G01X1099636Y786805D02*
X1168661D01*
G01X1098751Y788840D02*
G03X1099636Y787955I885J0D01*
G01X1097601Y788840D02*
G03X1099636Y786805I2035J0D01*
G01X1098751Y790340D02*
Y788840D01*
G01X1097601Y790340D02*
Y788840D01*
G01X1099636Y786805D02*
X1168661D01*
G01X1099636Y787955D02*
X1168782D01*
G01X1097601Y788840D02*
G03X1099636Y786805I2035J0D01*
G01X1098751Y788840D02*
G03X1099636Y787955I885J0D01*
G01X1097601Y790340D02*
Y788840D01*
G01X1098751Y790340D02*
Y788840D01*
G01X1147265Y780868D02*
X1207922Y767977D01*
G01X1147144Y779718D02*
X1207474Y766896D01*
G01X1103573Y780868D02*
X1147265D01*
G01X1103573Y779718D02*
X1147144D01*
G01X1102688Y781753D02*
G03X1103573Y780868I885J0D01*
G01X1101538Y781753D02*
G03X1103573Y779718I2035J0D01*
G01X1102688Y783253D02*
Y781753D01*
G01X1101538Y783253D02*
Y781753D01*
G01X1147144Y779718D02*
X1207474Y766896D01*
G01X1147265Y780868D02*
X1207922Y767977D01*
G01X1103573Y779718D02*
X1147144D01*
G01X1103573Y780868D02*
X1147265D01*
G01X1101538Y781753D02*
G03X1103573Y779718I2035J0D01*
G01X1102688Y781753D02*
G03X1103573Y780868I885J0D01*
G01X1101538Y783253D02*
Y781753D01*
G01X1102688Y783253D02*
Y781753D01*
G01X1141974Y773782D02*
X1208392Y759667D01*
G01X1141853Y772632D02*
X1207944Y758586D01*
G01X1099636Y773782D02*
X1141974D01*
G01X1099636Y772632D02*
X1141853D01*
G01X1098751Y774667D02*
G03X1099636Y773782I885J0D01*
G01X1097601Y774667D02*
G03X1099636Y772632I2035J0D01*
G01X1098751Y776167D02*
Y774667D01*
G01X1097601Y776167D02*
Y774667D01*
G01X1141853Y772632D02*
X1207944Y758586D01*
G01X1141974Y773782D02*
X1208392Y759667D01*
G01X1099636Y772632D02*
X1141853D01*
G01X1099636Y773782D02*
X1141974D01*
G01X1097601Y774667D02*
G03X1099636Y772632I2035J0D01*
G01X1098751Y774667D02*
G03X1099636Y773782I885J0D01*
G01X1097601Y776167D02*
Y774667D01*
G01X1098751Y776167D02*
Y774667D01*
G01X1096175Y815152D02*
X1082964D01*
G01X1096175Y816302D02*
X1082843D01*
G01X1098751Y817728D02*
G02X1096175Y815152I-2576J0D01*
G01X1097601Y817728D02*
G02X1096175Y816302I-1426J0D01*
G01X1098751Y818428D02*
Y817728D01*
G01X1097601Y818428D02*
Y817728D01*
G01X1096175Y816302D02*
X1082843D01*
G01X1096175Y815152D02*
X1082964D01*
G01X1097601Y817728D02*
G02X1096175Y816302I-1426J0D01*
G01X1098751Y817728D02*
G02X1096175Y815152I-2576J0D01*
G01X1097601Y818428D02*
Y817728D01*
G01X1098751Y818428D02*
Y817728D01*
G01X1100112Y822238D02*
X1065184D01*
G01X1100112Y823388D02*
X1065063D01*
G01X1102688Y824814D02*
G02X1100112Y822238I-2576J0D01*
G01X1101538Y824814D02*
G02X1100112Y823388I-1426J0D01*
G01X1102688Y825514D02*
Y824814D01*
G01X1101538Y825514D02*
Y824814D01*
G01X1100112Y823388D02*
X1065063D01*
G01X1100112Y822238D02*
X1065184D01*
G01X1101538Y824814D02*
G02X1100112Y823388I-1426J0D01*
G01X1102688Y824814D02*
G02X1100112Y822238I-2576J0D01*
G01X1101538Y825514D02*
Y824814D01*
G01X1102688Y825514D02*
Y824814D01*
G01X1091845Y829325D02*
X1071791Y833587D01*
G01X1091966Y830475D02*
X1071791Y834763D01*
G01X1096175Y829325D02*
X1091845D01*
G01X1096175Y830475D02*
X1091966D01*
G01X1098751Y831901D02*
G02X1096175Y829325I-2576J0D01*
G01X1097601Y831901D02*
G02X1096175Y830475I-1426J0D01*
G01X1098751Y832601D02*
Y831901D01*
G01X1097601Y832601D02*
Y831901D01*
G01X1091966Y830475D02*
X1071791Y834763D01*
G01X1091845Y829325D02*
X1071791Y833587D01*
G01X1096175Y830475D02*
X1091966D01*
G01X1096175Y829325D02*
X1091845D01*
G01X1097601Y831901D02*
G02X1096175Y830475I-1426J0D01*
G01X1098751Y831901D02*
G02X1096175Y829325I-2576J0D01*
G01X1097601Y832601D02*
Y831901D01*
G01X1098751Y832601D02*
Y831901D01*
G01X1088099Y836411D02*
X1064067Y841513D01*
G01X1088220Y837561D02*
X1064067Y842689D01*
G01X1100112Y836411D02*
X1088099D01*
G01X1100112Y837561D02*
X1088220D01*
G01X1102688Y838987D02*
G02X1100112Y836411I-2576J0D01*
G01X1101538Y838987D02*
G02X1100112Y837561I-1426J0D01*
G01X1102688Y839687D02*
Y838987D01*
G01X1101538Y839687D02*
Y838987D01*
G01X1088220Y837561D02*
X1064067Y842689D01*
G01X1088099Y836411D02*
X1064067Y841513D01*
G01X1100112Y837561D02*
X1088220D01*
G01X1100112Y836411D02*
X1088099D01*
G01X1101538Y838987D02*
G02X1100112Y837561I-1426J0D01*
G01X1102688Y838987D02*
G02X1100112Y836411I-2576J0D01*
G01X1101538Y839687D02*
Y838987D01*
G01X1102688Y839687D02*
Y838987D01*
G01X1096175Y843498D02*
X1084835D01*
G01X1096175Y844648D02*
X1084956D01*
G01X1098751Y846074D02*
G02X1096175Y843498I-2576J0D01*
G01X1097601Y846074D02*
G02X1096175Y844648I-1426J0D01*
G01X1098751Y846774D02*
Y846074D01*
G01X1097601Y846774D02*
Y846074D01*
G01X1096175Y844648D02*
X1084956D01*
G01X1096175Y843498D02*
X1084835D01*
G01X1097601Y846074D02*
G02X1096175Y844648I-1426J0D01*
G01X1098751Y846074D02*
G02X1096175Y843498I-2576J0D01*
G01X1097601Y846774D02*
Y846074D01*
G01X1098751Y846774D02*
Y846074D01*
G01X1100112Y850585D02*
X1081870D01*
G01X1100112Y851735D02*
X1081991D01*
G01X1102688Y853161D02*
G02X1100112Y850585I-2576J0D01*
G01X1101538Y853161D02*
G02X1100112Y851735I-1426J0D01*
G01X1102688Y853861D02*
Y853161D01*
G01X1101538Y853861D02*
Y853161D01*
G01X1100112Y851735D02*
X1081991D01*
G01X1100112Y850585D02*
X1081870D01*
G01X1101538Y853161D02*
G02X1100112Y851735I-1426J0D01*
G01X1102688Y853161D02*
G02X1100112Y850585I-2576J0D01*
G01X1101538Y853861D02*
Y853161D01*
G01X1102688Y853861D02*
Y853161D01*
G01X1089300Y765545D02*
X1076306Y762783D01*
G01X1089179Y766695D02*
X1075858Y763864D01*
G01X1100112Y765545D02*
X1089300D01*
G01X1100112Y766695D02*
X1089179D01*
G01X1102688Y768121D02*
G02X1100112Y765545I-2576J0D01*
G01X1101538Y768121D02*
G02X1100112Y766695I-1426J0D01*
G01X1102688Y768821D02*
Y768121D01*
G01X1101538Y768821D02*
Y768121D01*
G01X1089179Y766695D02*
X1075858Y763864D01*
G01X1089300Y765545D02*
X1076306Y762783D01*
G01X1100112Y766695D02*
X1089179D01*
G01X1100112Y765545D02*
X1089300D01*
G01X1101538Y768121D02*
G02X1100112Y766695I-1426J0D01*
G01X1102688Y768121D02*
G02X1100112Y765545I-2576J0D01*
G01X1101538Y768821D02*
Y768121D01*
G01X1102688Y768821D02*
Y768121D01*
G01X1147082Y878881D02*
X1326976Y901536D01*
G01X1147009Y880031D02*
X1326814Y902675D01*
G01X1099832Y878881D02*
X1147082D01*
G01X1099832Y880031D02*
X1147009D01*
G01X1098751Y877800D02*
G02X1099832Y878881I1081J0D01*
G01X1097601Y877800D02*
G02X1099832Y880031I2231J0D01*
G01X1098751Y876600D02*
Y877800D01*
G01X1097601Y876600D02*
Y877800D01*
G01X1147009Y880031D02*
X1326814Y902675D01*
G01X1147082Y878881D02*
X1326976Y901536D01*
G01X1099832Y880031D02*
X1147009D01*
G01X1099832Y878881D02*
X1147082D01*
G01X1097601Y877800D02*
G02X1099832Y880031I2231J0D01*
G01X1098751Y877800D02*
G02X1099832Y878881I1081J0D01*
G01X1097601Y876600D02*
Y877800D01*
G01X1098751Y876600D02*
Y877800D01*
G01X1145271Y885968D02*
X1302783Y911890D01*
G01X1145176Y887118D02*
X1223866Y900069D01*
G01X1103656Y885968D02*
X1145271D01*
G01X1103656Y887118D02*
X1145176D01*
G01X1102688Y885000D02*
G02X1103656Y885968I968J0D01*
G01X1101538Y885000D02*
G02X1103656Y887118I2118J0D01*
G01X1102688Y883900D02*
Y885000D01*
G01X1101538Y883900D02*
Y885000D01*
G01X1145271Y885968D02*
X1302783Y911890D01*
G01X1145176Y887118D02*
X1223866Y900069D01*
G01X1145271Y885968D02*
X1302783Y911890D01*
G01X1103656Y887118D02*
X1145176D01*
G01X1103656Y885968D02*
X1145271D01*
G01X1101538Y885000D02*
G02X1103656Y887118I2118J0D01*
G01X1102688Y885000D02*
G02X1103656Y885968I968J0D01*
G01X1101538Y883900D02*
Y885000D01*
G01X1102688Y883900D02*
Y885000D01*
G01X1145088Y893055D02*
X1190659Y904989D01*
G01X1144938Y894205D02*
X1190368Y906103D01*
G01X1100006Y893055D02*
X1145088D01*
G01X1100006Y894205D02*
X1144938D01*
G01X1098751Y891800D02*
G02X1100006Y893055I1255J0D01*
G01X1097601Y891800D02*
G02X1100006Y894205I2405J0D01*
G01X1098751Y891100D02*
Y891800D01*
G01X1097601Y891100D02*
Y891800D01*
G01X1144938Y894205D02*
X1190368Y906103D01*
G01X1145088Y893055D02*
X1190659Y904989D01*
G01X1100006Y894205D02*
X1144938D01*
G01X1100006Y893055D02*
X1145088D01*
G01X1097601Y891800D02*
G02X1100006Y894205I2405J0D01*
G01X1098751Y891800D02*
G02X1100006Y893055I1255J0D01*
G01X1097601Y891100D02*
Y891800D01*
G01X1098751Y891100D02*
Y891800D01*
G01X1142390Y901291D02*
X1251351Y964686D01*
G01X1142390Y901291D02*
X1251351Y964686D01*
G01X1142390Y901291D02*
X1251351Y964686D01*
G01X1142390Y901291D02*
X1251351Y964686D01*
G01X1142701Y900141D02*
X1206817Y937444D01*
G01X1142390Y901291D02*
X1251351Y964686D01*
G01X1103929Y900141D02*
X1142701D01*
G01X1103929Y901291D02*
X1142390D01*
G01X1102688Y898900D02*
G02X1103929Y900141I1241J0D01*
G01X1101538Y898900D02*
G02X1103929Y901291I2391J0D01*
G01X1102688Y898000D02*
Y898900D01*
G01X1101538Y898000D02*
Y898900D01*
G01X1142390Y901291D02*
X1251351Y964686D01*
G01X1142701Y900141D02*
X1206817Y937444D01*
G01X1103929Y901291D02*
X1142390D01*
G01X1103929Y900141D02*
X1142701D01*
G01X1101538Y898900D02*
G02X1103929Y901291I2391J0D01*
G01X1102688Y898900D02*
G02X1103929Y900141I1241J0D01*
G01X1101538Y898000D02*
Y898900D01*
G01X1102688Y898000D02*
Y898900D01*
G01X1141791Y864708D02*
X1342389Y883412D01*
G01X1141737Y865858D02*
X1342266Y884556D01*
G01X1099959Y864708D02*
X1141791D01*
G01X1099959Y865858D02*
X1141737D01*
G01X1098751Y863500D02*
G02X1099959Y864708I1208J0D01*
G01X1097601Y863500D02*
G02X1099959Y865858I2358J0D01*
G01X1098751Y862600D02*
Y863500D01*
G01X1097601Y862600D02*
Y863500D01*
G01X1141737Y865858D02*
X1342266Y884556D01*
G01X1141791Y864708D02*
X1342389Y883412D01*
G01X1099959Y865858D02*
X1141737D01*
G01X1099959Y864708D02*
X1141791D01*
G01X1097601Y863500D02*
G02X1099959Y865858I2358J0D01*
G01X1098751Y863500D02*
G02X1099959Y864708I1208J0D01*
G01X1097601Y862600D02*
Y863500D01*
G01X1098751Y862600D02*
Y863500D01*
G01X1143956Y872945D02*
X1331392Y893070D01*
G01X1144018Y871795D02*
X1331514Y891926D01*
G01X1143956Y872945D02*
X1331392Y893070D01*
G01X1103883Y871795D02*
X1144018D01*
G01X1103883Y872945D02*
X1143956D01*
G01X1102688Y870600D02*
G02X1103883Y871795I1195J0D01*
G01X1101538Y870600D02*
G02X1103883Y872945I2345J0D01*
G01X1102688Y869600D02*
Y870600D01*
G01X1101538Y869600D02*
Y870600D01*
G01X1143956Y872945D02*
X1331392Y893070D01*
G01X1144018Y871795D02*
X1331514Y891926D01*
G01X1103883Y872945D02*
X1143956D01*
G01X1103883Y871795D02*
X1144018D01*
G01X1101538Y870600D02*
G02X1103883Y872945I2345J0D01*
G01X1102688Y870600D02*
G02X1103883Y871795I1195J0D01*
G01X1101538Y869600D02*
Y870600D01*
G01X1102688Y869600D02*
Y870600D01*
G01Y938200D02*
G02X1100112Y935624I-2576J0D01*
G01X1101538Y938200D02*
G02X1100112Y936774I-1426J0D01*
G01X1102688Y938900D02*
Y938200D01*
G01X1101538Y938900D02*
Y938200D01*
G01D02*
G02X1100112Y936774I-1426J0D01*
G01X1102688Y938200D02*
G02X1100112Y935624I-2576J0D01*
G01X1101538Y938900D02*
Y938200D01*
G01X1102688Y938900D02*
Y938200D01*
G01X1096175Y928537D02*
X1054857D01*
G01X1096175Y929687D02*
X1054978D01*
G01X1098751Y931113D02*
G02X1096175Y928537I-2576J0D01*
G01X1097601Y931113D02*
G02X1096175Y929687I-1426J0D01*
G01X1098751Y931813D02*
Y931113D01*
G01X1097601Y931813D02*
Y931113D01*
G01X1096175Y929687D02*
X1054978D01*
G01X1096175Y928537D02*
X1054857D01*
G01X1097601Y931113D02*
G02X1096175Y929687I-1426J0D01*
G01X1098751Y931113D02*
G02X1096175Y928537I-2576J0D01*
G01X1097601Y931813D02*
Y931113D01*
G01X1098751Y931813D02*
Y931113D01*
G01X1100112Y921451D02*
X1058581D01*
G01X1100112Y922601D02*
X1058702D01*
G01X1102688Y924027D02*
G02X1100112Y921451I-2576J0D01*
G01X1101538Y924027D02*
G02X1100112Y922601I-1426J0D01*
G01X1102688Y924727D02*
Y924027D01*
G01X1101538Y924727D02*
Y924027D01*
G01X1100112Y922601D02*
X1058702D01*
G01X1100112Y921451D02*
X1058581D01*
G01X1101538Y924027D02*
G02X1100112Y922601I-1426J0D01*
G01X1102688Y924027D02*
G02X1100112Y921451I-2576J0D01*
G01X1101538Y924727D02*
Y924027D01*
G01X1102688Y924727D02*
Y924027D01*
G01X1096175Y914364D02*
X1062822D01*
G01X1096175Y915514D02*
X1062943D01*
G01X1098751Y916940D02*
G02X1096175Y914364I-2576J0D01*
G01X1097601Y916940D02*
G02X1096175Y915514I-1426J0D01*
G01X1098751Y917640D02*
Y916940D01*
G01X1097601Y917640D02*
Y916940D01*
G01X1096175Y915514D02*
X1062943D01*
G01X1096175Y914364D02*
X1062822D01*
G01X1097601Y916940D02*
G02X1096175Y915514I-1426J0D01*
G01X1098751Y916940D02*
G02X1096175Y914364I-2576J0D01*
G01X1097601Y917640D02*
Y916940D01*
G01X1098751Y917640D02*
Y916940D01*
G01X1100112Y907278D02*
X1065724D01*
G01X1100112Y908428D02*
X1065845D01*
G01X1102688Y909854D02*
G02X1100112Y907278I-2576J0D01*
G01X1101538Y909854D02*
G02X1100112Y908428I-1426J0D01*
G01X1102688Y910554D02*
Y909854D01*
G01X1101538Y910554D02*
Y909854D01*
G01X1100112Y908428D02*
X1065845D01*
G01X1100112Y907278D02*
X1065724D01*
G01X1101538Y909854D02*
G02X1100112Y908428I-1426J0D01*
G01X1102688Y909854D02*
G02X1100112Y907278I-2576J0D01*
G01X1101538Y910554D02*
Y909854D01*
G01X1102688Y910554D02*
Y909854D01*
G01X1096175Y900191D02*
X1068479D01*
G01X1096175Y901341D02*
X1068600D01*
G01X1098751Y902767D02*
G02X1096175Y900191I-2576J0D01*
G01X1097601Y902767D02*
G02X1096175Y901341I-1426J0D01*
G01X1098751Y903467D02*
Y902767D01*
G01X1097601Y903467D02*
Y902767D01*
G01X1096175Y901341D02*
X1068600D01*
G01X1096175Y900191D02*
X1068479D01*
G01X1097601Y902767D02*
G02X1096175Y901341I-1426J0D01*
G01X1098751Y902767D02*
G02X1096175Y900191I-2576J0D01*
G01X1097601Y903467D02*
Y902767D01*
G01X1098751Y903467D02*
Y902767D01*
G01X1232239Y397909D02*
X1259575Y61567D01*
G01X1231098Y397742D02*
X1258425Y61520D01*
G01X1231098Y397742D02*
X1258425Y61520D01*
G01X1232239Y397909D02*
X1259575Y61567D01*
G01X1227711Y489645D02*
X1506850Y59807D01*
G01X1227711Y489645D02*
X1506850Y59807D01*
G01X1227711Y489645D02*
X1506850Y59807D01*
G01X1227711Y489645D02*
X1506850Y59807D01*
G01X1228792Y490093D02*
X1488302Y90481D01*
G01X1227711Y489645D02*
X1506850Y59807D01*
G01X1227711Y489645D02*
X1506850Y59807D01*
G01X1228792Y490093D02*
X1488302Y90481D01*
G01X1221776Y480185D02*
X1327537Y317332D01*
G01X1221776Y480185D02*
X1327537Y317332D01*
G01X1221776Y480185D02*
X1327537Y317332D01*
G01X1221776Y480185D02*
X1327537Y317332D01*
G01X1222857Y480633D02*
X1313841Y340533D01*
G01X1221776Y480185D02*
X1327537Y317332D01*
G01X1221776Y480185D02*
X1327537Y317332D01*
G01X1222857Y480633D02*
X1313841Y340533D01*
G01X1209512Y504925D02*
X1232239Y397909D01*
G01X1182029Y628784D02*
X1231098Y397742D01*
G01X1182029Y628784D02*
X1231098Y397742D01*
G01X1182029Y628784D02*
X1231098Y397742D01*
G01X1182029Y628784D02*
X1231098Y397742D01*
G01X1182029Y628784D02*
X1231098Y397742D01*
G01X1182029Y628784D02*
X1231098Y397742D01*
G01X1209512Y504925D02*
X1232239Y397909D01*
G01X1219280Y653990D02*
X1251078Y504426D01*
G01X1218199Y653542D02*
X1249997Y503978D01*
G01X1218199Y653542D02*
X1249997Y503978D01*
G01X1219280Y653990D02*
X1251078Y504426D01*
G01X1243496Y499115D02*
X1358501Y322024D01*
G01X1242415Y498667D02*
X1357669Y321192D01*
G01X1211606Y649138D02*
X1243496Y499115D01*
G01X1210525Y648690D02*
X1242415Y498667D01*
G01D02*
X1357669Y321192D01*
G01X1243496Y499115D02*
X1358501Y322024D01*
G01X1210525Y648690D02*
X1242415Y498667D01*
G01X1211606Y649138D02*
X1243496Y499115D01*
G01X1236546Y495181D02*
X1352049Y317323D01*
G01X1235465Y494733D02*
X1351217Y316491D01*
G01X1205942Y639166D02*
X1236546Y495181D01*
G01X1204861Y638718D02*
X1235465Y494733D01*
G01D02*
X1351217Y316491D01*
G01X1236546Y495181D02*
X1352049Y317323D01*
G01X1204861Y638718D02*
X1235465Y494733D01*
G01X1205942Y639166D02*
X1236546Y495181D01*
G01X1198093Y634519D02*
X1228792Y490093D01*
G01X1197012Y634071D02*
X1227711Y489645D01*
G01X1197012Y634071D02*
X1227711Y489645D01*
G01X1198093Y634519D02*
X1228792Y490093D01*
G01X1190613Y632330D02*
X1222857Y480633D01*
G01X1189532Y631882D02*
X1221776Y480185D01*
G01X1189532Y631882D02*
X1221776Y480185D01*
G01X1190613Y632330D02*
X1222857Y480633D01*
G01X1208639Y509033D02*
X1208951Y507566D01*
G01X1207767Y513142D02*
X1208078Y511674D01*
G01X1206894Y517250D02*
X1207206Y515783D01*
G01X1183110Y629231D02*
X1206333Y519891D01*
G01X1208639Y509033D02*
X1208951Y507566D01*
G01X1207767Y513142D02*
X1208078Y511674D01*
G01X1206894Y517250D02*
X1207206Y515783D01*
G01X1183110Y629231D02*
X1206333Y519891D01*
G01X1189255Y700225D02*
X1219280Y653990D01*
G01X1188423Y699393D02*
X1218199Y653542D01*
G01X1188423Y699393D02*
X1218199Y653542D01*
G01X1189255Y700225D02*
X1219280Y653990D01*
G01X1182760Y693557D02*
X1211606Y649138D01*
G01X1181928Y692725D02*
X1210525Y648690D01*
G01X1181928Y692725D02*
X1210525Y648690D01*
G01X1182760Y693557D02*
X1211606Y649138D01*
G01X1169931Y694617D02*
X1205942Y639166D01*
G01X1169099Y693785D02*
X1204861Y638718D01*
G01X1169099Y693785D02*
X1204861Y638718D01*
G01X1169931Y694617D02*
X1205942Y639166D01*
G01X1159934Y693278D02*
X1198093Y634519D01*
G01X1159102Y692446D02*
X1197012Y634071D01*
G01X1159102Y692446D02*
X1197012Y634071D01*
G01X1159934Y693278D02*
X1198093Y634519D01*
G01X1154519Y687910D02*
X1190613Y632330D01*
G01X1153688Y687078D02*
X1189532Y631882D01*
G01X1153688Y687078D02*
X1189532Y631882D01*
G01X1154519Y687910D02*
X1190613Y632330D01*
G01X1224644Y755745D02*
X1382638Y512464D01*
G01X1224644Y755745D02*
X1382638Y512464D01*
G01X1224644Y755745D02*
X1382638Y512464D01*
G01X1224644Y755745D02*
X1382638Y512464D01*
G01X1225476Y756577D02*
X1266027Y694136D01*
G01X1224644Y755745D02*
X1382638Y512464D01*
G01X1207922Y767977D02*
X1225476Y756577D01*
G01X1207474Y766896D02*
X1224644Y755745D01*
G01D02*
X1382638Y512464D01*
G01X1225476Y756577D02*
X1266027Y694136D01*
G01X1207474Y766896D02*
X1224644Y755745D01*
G01X1207922Y767977D02*
X1225476Y756577D01*
G01X1234445Y726395D02*
X1268828Y564712D01*
G01X1234445Y726395D02*
X1268828Y564712D01*
G01X1234445Y726395D02*
X1268828Y564712D01*
G01X1234445Y726395D02*
X1268828Y564712D01*
G01X1235526Y726843D02*
X1262345Y600729D01*
G01X1234445Y726395D02*
X1268828Y564712D01*
G01X1218460Y753128D02*
X1235526Y726843D01*
G01X1217628Y752296D02*
X1234445Y726395D01*
G01X1208392Y759667D02*
X1218460Y753128D01*
G01X1207944Y758586D02*
X1217628Y752296D01*
G01X1234445Y726395D02*
X1268828Y564712D01*
G01X1235526Y726843D02*
X1262345Y600729D01*
G01X1217628Y752296D02*
X1234445Y726395D01*
G01X1218460Y753128D02*
X1235526Y726843D01*
G01X1207944Y758586D02*
X1217628Y752296D01*
G01X1208392Y759667D02*
X1218460Y753128D01*
G01X1160397Y718966D02*
X1189255Y700225D01*
G01X1159949Y717885D02*
X1188423Y699393D01*
G01X1159949Y717885D02*
X1188423Y699393D01*
G01X1160397Y718966D02*
X1189255Y700225D01*
G01X1150590Y714452D02*
X1182760Y693557D01*
G01X1150159Y713360D02*
X1181928Y692725D01*
G01X1150159Y713360D02*
X1181928Y692725D01*
G01X1150590Y714452D02*
X1182760Y693557D01*
G01X1151063Y706869D02*
X1169931Y694617D01*
G01X1150615Y705788D02*
X1169099Y693785D01*
G01X1150615Y705788D02*
X1169099Y693785D01*
G01X1151063Y706869D02*
X1169931Y694617D01*
G01X1149224Y700233D02*
X1159934Y693278D01*
G01X1149224Y700233D02*
X1159934Y693278D01*
G01X1186469Y809215D02*
X1350519Y774350D01*
G01X1186348Y808065D02*
X1350071Y773269D01*
G01X1186348Y808065D02*
X1350071Y773269D01*
G01X1186469Y809215D02*
X1350519Y774350D01*
G01X1189361Y802128D02*
X1344619Y769211D01*
G01X1189240Y800978D02*
X1344172Y768130D01*
G01X1189240Y800978D02*
X1344172Y768130D01*
G01X1189361Y802128D02*
X1344619Y769211D01*
G01X1193494Y795042D02*
X1317867Y768605D01*
G01X1193373Y793892D02*
X1317420Y767524D01*
G01X1193373Y793892D02*
X1317420Y767524D01*
G01X1193494Y795042D02*
X1317867Y768605D01*
G01X1168782Y787955D02*
X1316945Y756462D01*
G01X1168661Y786805D02*
X1316497Y755381D01*
G01X1168661Y786805D02*
X1316497Y755381D01*
G01X1168782Y787955D02*
X1316945Y756462D01*
G01X1223866Y900069D02*
X1302555Y913018D01*
G01X1223866Y900069D02*
X1302555Y913018D01*
G01X1242164Y918478D02*
X1297328Y932926D01*
G01X1190368Y906103D02*
X1296973Y934022D01*
G01X1238101Y917414D02*
X1239552Y917794D01*
G01X1190368Y906103D02*
X1296973Y934022D01*
G01X1234038Y916350D02*
X1235489Y916730D01*
G01X1190368Y906103D02*
X1296973Y934022D01*
G01X1229975Y915286D02*
X1231427Y915666D01*
G01X1190368Y906103D02*
X1296973Y934022D01*
G01X1190659Y904989D02*
X1227364Y914602D01*
G01X1190368Y906103D02*
X1296973Y934022D01*
G01X1190368Y906103D02*
X1296973Y934022D01*
G01X1242164Y918478D02*
X1297328Y932926D01*
G01X1238101Y917414D02*
X1239552Y917794D01*
G01X1234038Y916350D02*
X1235489Y916730D01*
G01X1229975Y915286D02*
X1231427Y915666D01*
G01X1190659Y904989D02*
X1227364Y914602D01*
G01X1220040Y945138D02*
X1251662Y963536D01*
G01X1216410Y943026D02*
X1217706Y943781D01*
G01X1212780Y940914D02*
X1214076Y941669D01*
G01X1209149Y938802D02*
X1210446Y939556D01*
G01X1220040Y945138D02*
X1251662Y963536D01*
G01X1216410Y943026D02*
X1217706Y943781D01*
G01X1212780Y940914D02*
X1214076Y941669D01*
G01X1209149Y938802D02*
X1210446Y939556D01*
G01X1259575Y61567D02*
Y54325D01*
G01X1258425Y61520D02*
Y54325D01*
G01Y61520D02*
Y54325D01*
G01X1259575Y61567D02*
Y54325D01*
G01X1328586Y317829D02*
X1358901Y222805D01*
G01X1327537Y317332D02*
X1357778Y222541D01*
G01X1327537Y317332D02*
X1357778Y222541D01*
G01X1328586Y317829D02*
X1358901Y222805D01*
G01X1251078Y504426D02*
X1365678Y327958D01*
G01X1249997Y503978D02*
X1364846Y327126D01*
G01X1249997Y503978D02*
X1364846Y327126D01*
G01X1251078Y504426D02*
X1365678Y327958D01*
G01X1322349Y327433D02*
X1328586Y317829D01*
G01X1320017Y331023D02*
X1320834Y329765D01*
G01X1317686Y334612D02*
X1318503Y333354D01*
G01X1315355Y338202D02*
X1316172Y336944D01*
G01X1322349Y327433D02*
X1328586Y317829D01*
G01X1320017Y331023D02*
X1320834Y329765D01*
G01X1317686Y334612D02*
X1318503Y333354D01*
G01X1315355Y338202D02*
X1316172Y336944D01*
G01X1259575Y515098D02*
Y507025D01*
G01X1258425Y515219D02*
Y507025D01*
G01X1270004Y564713D02*
X1259575Y515098D01*
G01X1268828Y564711D02*
X1258425Y515219D01*
G01X1265528Y585764D02*
X1270004Y564713D01*
G01X1258425Y515219D02*
Y507025D01*
G01X1259575Y515098D02*
Y507025D01*
G01X1268828Y564711D02*
X1258425Y515219D01*
G01X1270004Y564713D02*
X1259575Y515098D01*
G01X1265528Y585764D02*
X1270004Y564713D01*
G01X1274360Y681305D02*
X1383788Y512805D01*
G01X1274360Y681305D02*
X1383788Y512805D01*
G01X1264654Y589872D02*
X1264966Y588405D01*
G01X1263780Y593980D02*
X1264092Y592513D01*
G01X1262907Y598088D02*
X1263219Y596621D01*
G01X1264654Y589872D02*
X1264966Y588405D01*
G01X1263780Y593980D02*
X1264092Y592513D01*
G01X1262907Y598088D02*
X1263219Y596621D01*
G01X1317867Y768605D02*
X1592079Y590610D01*
G01X1317420Y767524D02*
X1591247Y589778D01*
G01X1317420Y767524D02*
X1591247Y589778D01*
G01X1317867Y768605D02*
X1592079Y590610D01*
G01X1316945Y756462D02*
X1400977Y701891D01*
G01X1316497Y755381D02*
X1400145Y701059D01*
G01X1316497Y755381D02*
X1400145Y701059D01*
G01X1316945Y756462D02*
X1400977Y701891D01*
G01X1272073Y684827D02*
X1272890Y683569D01*
G01X1269785Y688350D02*
X1270602Y687092D01*
G01X1267498Y691872D02*
X1268314Y690614D01*
G01X1272073Y684827D02*
X1272890Y683569D01*
G01X1269785Y688350D02*
X1270602Y687092D01*
G01X1267498Y691872D02*
X1268314Y690614D01*
G01X1326976Y901536D02*
X1526405Y933299D01*
G01X1326814Y902675D02*
X1426477Y918548D01*
G01X1326976Y901536D02*
X1526405Y933299D01*
G01X1326976Y901536D02*
X1526405Y933299D01*
G01X1326814Y902675D02*
X1426477Y918548D01*
G01X1326976Y901536D02*
X1526405Y933299D01*
G01X1302783Y911890D02*
X1401601Y934503D01*
G01X1302555Y913018D02*
X1401310Y935617D01*
G01X1302555Y913018D02*
X1401310Y935617D01*
G01X1302783Y911890D02*
X1401601Y934503D01*
G01X1297328Y932926D02*
X1378990Y963556D01*
G01X1296973Y934022D02*
X1378781Y964706D01*
G01X1296973Y934022D02*
X1378781Y964706D01*
G01X1297328Y932926D02*
X1378990Y963556D01*
G01X1331392Y893070D02*
X1695688Y944695D01*
G01X1331392Y893070D02*
X1695688Y944695D01*
G01X1331392Y893070D02*
X1695688Y944695D01*
G01X1331392Y893070D02*
X1695688Y944695D01*
G01X1331554Y891931D02*
X1590897Y928683D01*
G01X1331392Y893070D02*
X1695688Y944695D01*
G01X1331514Y891926D02*
X1331554Y891931D01*
G01X1331392Y893070D02*
X1695688Y944695D01*
G01X1331392Y893070D02*
X1695688Y944695D01*
G01X1331554Y891931D02*
X1590897Y928683D01*
G01X1331514Y891926D02*
X1331554Y891931D01*
G01X1331514Y891926D02*
X1331554Y891931D01*
G01X1251662Y963536D02*
X1256790D01*
G01X1251351Y964686D02*
X1256790D01*
G01X1251351D02*
X1256790D01*
G01X1251662Y963536D02*
X1256790D01*
G01X1383788Y60652D02*
Y54338D01*
G01X1382638Y60564D02*
Y54338D01*
G01X1358901Y222805D02*
X1383788Y60652D01*
G01X1357778Y222541D02*
X1382638Y60564D01*
G01D02*
Y54338D01*
G01X1383788Y60652D02*
Y54338D01*
G01X1357778Y222541D02*
X1382638Y60564D01*
G01X1358901Y222805D02*
X1383788Y60652D01*
G01X1364846Y327126D02*
X1668347Y130030D01*
G01X1364846Y327126D02*
X1668347Y130030D01*
G01X1364846Y327126D02*
X1668347Y130030D01*
G01X1364846Y327126D02*
X1668347Y130030D01*
G01X1365678Y327958D02*
X1548941Y208945D01*
G01X1364846Y327126D02*
X1668347Y130030D01*
G01X1364846Y327126D02*
X1668347Y130030D01*
G01X1365678Y327958D02*
X1548941Y208945D01*
G01X1357669Y321192D02*
X1555116Y192972D01*
G01X1357669Y321192D02*
X1555116Y192972D01*
G01X1432035Y274272D02*
X1433293Y273455D01*
G01X1357669Y321192D02*
X1555116Y192972D01*
G01X1358501Y322024D02*
X1429704Y275786D01*
G01X1357669Y321192D02*
X1555116Y192972D01*
G01X1357669Y321192D02*
X1555116Y192972D01*
G01X1432035Y274272D02*
X1433293Y273455D01*
G01X1358501Y322024D02*
X1429704Y275786D01*
G01X1351217Y316491D02*
X1552732Y185630D01*
G01X1351217Y316491D02*
X1552732Y185630D01*
G01X1351217Y316491D02*
X1552732Y185630D01*
G01X1351217Y316491D02*
X1552732Y185630D01*
G01X1352049Y317323D02*
X1473465Y238477D01*
G01X1351217Y316491D02*
X1552732Y185630D01*
G01X1351217Y316491D02*
X1552732Y185630D01*
G01X1352049Y317323D02*
X1473465Y238477D01*
G01X1383788Y512805D02*
Y507038D01*
G01X1382638Y512464D02*
Y507038D01*
G01Y512464D02*
Y507038D01*
G01X1383788Y512805D02*
Y507038D01*
G01X1400145Y701059D02*
X1504844Y539837D01*
G01X1400145Y701059D02*
X1504844Y539837D01*
G01X1400145Y701059D02*
X1504844Y539837D01*
G01X1400145Y701059D02*
X1504844Y539837D01*
G01X1400977Y701891D02*
X1485788Y571293D01*
G01X1400145Y701059D02*
X1504844Y539837D01*
G01X1400145Y701059D02*
X1504844Y539837D01*
G01X1400977Y701891D02*
X1485788Y571293D01*
G01X1350071Y773269D02*
X1683749Y556577D01*
G01X1350071Y773269D02*
X1683749Y556577D01*
G01X1350071Y773269D02*
X1683749Y556577D01*
G01X1350071Y773269D02*
X1683749Y556577D01*
G01X1350519Y774350D02*
X1438919Y716943D01*
G01X1350071Y773269D02*
X1683749Y556577D01*
G01X1350071Y773269D02*
X1683749Y556577D01*
G01X1350519Y774350D02*
X1438919Y716943D01*
G01X1344172Y768130D02*
X1721445Y523128D01*
G01X1344172Y768130D02*
X1721445Y523128D01*
G01X1344172Y768130D02*
X1721445Y523128D01*
G01X1344172Y768130D02*
X1721445Y523128D01*
G01X1344619Y769211D02*
X1607083Y598767D01*
G01X1344172Y768130D02*
X1721445Y523128D01*
G01X1344172Y768130D02*
X1721445Y523128D01*
G01X1344619Y769211D02*
X1607083Y598767D01*
G01X1426477Y918548D02*
X1468384Y925223D01*
G01X1426477Y918548D02*
X1468384Y925223D01*
G01X1434385Y944154D02*
X1500089Y963496D01*
G01X1401310Y935617D02*
X1499923Y964646D01*
G01X1430356Y942968D02*
X1431795Y943392D01*
G01X1401310Y935617D02*
X1499923Y964646D01*
G01X1426327Y941782D02*
X1427766Y942206D01*
G01X1401310Y935617D02*
X1499923Y964646D01*
G01X1422298Y940596D02*
X1423737Y941020D01*
G01X1401310Y935617D02*
X1499923Y964646D01*
G01X1401601Y934503D02*
X1419708Y939833D01*
G01X1401310Y935617D02*
X1499923Y964646D01*
G01X1401310Y935617D02*
X1499923Y964646D01*
G01X1434385Y944154D02*
X1500089Y963496D01*
G01X1430356Y942968D02*
X1431795Y943392D01*
G01X1426327Y941782D02*
X1427766Y942206D01*
G01X1422298Y940596D02*
X1423737Y941020D01*
G01X1401601Y934503D02*
X1419708Y939833D01*
G01X1342266Y884556D02*
X1768774Y936846D01*
G01X1342266Y884556D02*
X1768774Y936846D01*
G01X1342266Y884556D02*
X1768774Y936846D01*
G01X1342266Y884556D02*
X1768774Y936846D01*
G01X1342389Y883412D02*
X1711916Y928715D01*
G01X1342266Y884556D02*
X1768774Y936846D01*
G01X1342266Y884556D02*
X1768774Y936846D01*
G01X1342389Y883412D02*
X1711916Y928715D01*
G01X1378990Y963556D02*
X1381056D01*
G01X1378781Y964706D02*
X1381056D01*
G01X1378781D02*
X1381056D01*
G01X1378990Y963556D02*
X1381056D01*
G01X1508000Y60148D02*
Y54250D01*
G01X1506850Y59807D02*
Y54250D01*
G01X1496809Y77381D02*
X1508000Y60148D01*
G01X1494478Y80970D02*
X1495295Y79712D01*
G01X1492147Y84560D02*
X1492964Y83302D01*
G01X1489816Y88149D02*
X1490633Y86891D01*
G01X1506850Y59807D02*
Y54250D01*
G01X1508000Y60148D02*
Y54250D01*
G01X1496809Y77381D02*
X1508000Y60148D01*
G01X1494478Y80970D02*
X1495295Y79712D01*
G01X1492147Y84560D02*
X1492964Y83302D01*
G01X1489816Y88149D02*
X1490633Y86891D01*
G01X1442804Y267279D02*
X1753490Y65523D01*
G01X1439214Y269610D02*
X1440472Y268793D01*
G01X1435625Y271941D02*
X1436883Y271124D01*
G01X1442804Y267279D02*
X1753490Y65523D01*
G01X1442804Y267279D02*
X1753490Y65523D01*
G01X1439214Y269610D02*
X1440472Y268793D01*
G01X1435625Y271941D02*
X1436883Y271124D01*
G01X1486565Y229970D02*
X1553410Y186561D01*
G01X1482976Y232301D02*
X1484234Y231484D01*
G01X1479386Y234632D02*
X1480644Y233815D01*
G01X1475797Y236963D02*
X1477055Y236146D01*
G01X1486565Y229970D02*
X1553410Y186561D01*
G01X1482976Y232301D02*
X1484234Y231484D01*
G01X1479386Y234632D02*
X1480644Y233815D01*
G01X1475797Y236963D02*
X1477055Y236146D01*
G01X1508000Y530521D02*
Y507050D01*
G01X1506850Y530400D02*
Y507050D01*
G01X1505925Y540285D02*
X1508000Y530521D01*
G01X1504844Y539837D02*
X1506850Y530400D01*
G01X1494121Y558462D02*
X1505925Y540285D01*
G01X1491833Y561984D02*
X1492650Y560726D01*
G01X1489546Y565506D02*
X1490363Y564248D01*
G01X1487258Y569029D02*
X1488075Y567771D01*
G01X1506850Y530400D02*
Y507050D01*
G01X1508000Y530521D02*
Y507050D01*
G01X1504844Y539837D02*
X1506850Y530400D01*
G01X1505925Y540285D02*
X1508000Y530521D01*
G01X1494121Y558462D02*
X1505925Y540285D01*
G01X1491833Y561984D02*
X1492650Y560726D01*
G01X1489546Y565506D02*
X1490363Y564248D01*
G01X1487258Y569029D02*
X1488075Y567771D01*
G01X1451750Y708610D02*
X1684197Y557658D01*
G01X1451750Y708610D02*
X1684197Y557658D01*
G01X1448228Y710897D02*
X1449486Y710080D01*
G01X1444705Y713185D02*
X1445963Y712368D01*
G01X1441183Y715472D02*
X1442441Y714655D01*
G01X1448228Y710897D02*
X1449486Y710080D01*
G01X1444705Y713185D02*
X1445963Y712368D01*
G01X1441183Y715472D02*
X1442441Y714655D01*
G01X1526142Y934422D02*
X1625026Y965206D01*
G01X1526142Y934422D02*
X1625026Y965206D01*
G01X1526142Y934422D02*
X1625026Y965206D01*
G01X1526405Y933299D02*
X1604476Y957603D01*
G01X1526142Y934422D02*
X1625026Y965206D01*
G01X1468384Y925223D02*
X1526142Y934422D01*
G01D02*
X1625026Y965206D01*
G01X1526405Y933299D02*
X1604476Y957603D01*
G01X1468384Y925223D02*
X1526142Y934422D01*
G01X1500089Y963496D02*
X1505056D01*
G01X1499923Y964646D02*
X1505056D01*
G01X1499923D02*
X1505056D01*
G01X1500089Y963496D02*
X1505056D01*
G01X1610957Y130886D02*
X1632213Y58285D01*
G01X1609895Y130419D02*
X1631063Y58120D01*
G01X1609895Y130419D02*
X1631063Y58120D01*
G01X1610957Y130886D02*
X1632213Y58285D01*
G01X1561773Y200612D02*
X1668795Y131111D01*
G01X1561773Y200612D02*
X1668795Y131111D01*
G01X1555118Y192971D02*
X1752568Y64749D01*
G01X1555118Y192971D02*
X1752568Y64749D01*
G01X1600350Y148426D02*
X1610957Y130886D01*
G01X1599469Y147659D02*
X1609895Y130419D01*
G01X1553410Y186561D02*
X1600350Y148426D01*
G01X1552732Y185630D02*
X1599469Y147659D01*
G01D02*
X1609895Y130419D01*
G01X1600350Y148426D02*
X1610957Y130886D01*
G01X1552732Y185630D02*
X1599469Y147659D01*
G01X1553410Y186561D02*
X1600350Y148426D01*
G01X1558250Y202900D02*
X1559508Y202083D01*
G01X1554728Y205187D02*
X1555986Y204370D01*
G01X1551205Y207475D02*
X1552463Y206658D01*
G01X1558250Y202900D02*
X1559508Y202083D01*
G01X1554728Y205187D02*
X1555986Y204370D01*
G01X1551205Y207475D02*
X1552463Y206658D01*
G01X1555116Y192972D02*
X1555117D01*
G01X1555116D02*
X1555117D01*
G01X1607188Y567344D02*
X1630832Y530937D01*
G01X1591247Y589778D02*
X1629751Y530489D01*
G01X1604901Y570867D02*
X1605718Y569609D01*
G01X1591247Y589778D02*
X1629751Y530489D01*
G01X1591247Y589778D02*
X1629751Y530489D01*
G01X1591247Y589778D02*
X1629751Y530489D01*
G01X1591247Y589778D02*
X1629751Y530489D01*
G01X1591247Y589778D02*
X1629751Y530489D01*
G01X1607188Y567344D02*
X1630832Y530937D01*
G01X1604901Y570867D02*
X1605718Y569609D01*
G01X1619915Y590435D02*
X1721893Y524209D01*
G01X1616392Y592722D02*
X1617650Y591905D01*
G01X1612870Y595009D02*
X1614128Y594193D01*
G01X1609347Y597297D02*
X1610605Y596480D01*
G01X1619915Y590435D02*
X1721893Y524209D01*
G01X1616392Y592722D02*
X1617650Y591905D01*
G01X1612870Y595009D02*
X1614128Y594193D01*
G01X1609347Y597297D02*
X1610605Y596480D01*
G01X1602613Y574389D02*
X1603430Y573131D01*
G01X1600326Y577911D02*
X1601143Y576653D01*
G01X1592079Y590610D02*
X1598855Y580176D01*
G01X1602613Y574389D02*
X1603430Y573131D01*
G01X1600326Y577911D02*
X1601143Y576653D01*
G01X1592079Y590610D02*
X1598855Y580176D01*
G01X1606046Y930830D02*
X1695968Y943573D01*
G01X1601887Y930240D02*
X1603372Y930451D01*
G01X1597729Y929651D02*
X1599214Y929861D01*
G01X1593570Y929062D02*
X1595055Y929272D01*
G01X1606046Y930830D02*
X1695968Y943573D01*
G01X1601887Y930240D02*
X1603372Y930451D01*
G01X1597729Y929651D02*
X1599214Y929861D01*
G01X1593570Y929062D02*
X1595055Y929272D01*
G01X1625201Y964056D02*
X1629556D01*
G01X1625026Y965206D02*
X1629556D01*
G01X1615074Y960903D02*
X1625201Y964056D01*
G01X1611064Y959654D02*
X1612496Y960100D01*
G01X1607054Y958406D02*
X1608486Y958852D01*
G01X1625026Y965206D02*
X1629556D01*
G01X1625201Y964056D02*
X1629556D01*
G01X1615074Y960903D02*
X1625201Y964056D01*
G01X1611064Y959654D02*
X1612496Y960100D01*
G01X1607054Y958406D02*
X1608486Y958852D01*
G01X1632213Y58285D02*
Y54263D01*
G01X1631063Y58120D02*
Y54263D01*
G01Y58120D02*
Y54263D01*
G01X1632213Y58285D02*
Y54263D01*
G01X1668795Y131111D02*
X1840251Y94664D01*
G01X1668347Y130030D02*
X1839763Y93592D01*
G01X1668347Y130030D02*
X1839763Y93592D01*
G01X1668795Y131111D02*
X1840251Y94664D01*
G01X1684197Y557658D02*
X1873153Y517494D01*
G01X1683749Y556577D02*
X1872705Y516413D01*
G01X1683749Y556577D02*
X1872705Y516413D01*
G01X1684197Y557658D02*
X1873153Y517494D01*
G01X1721445Y523128D02*
X1753311Y516354D01*
G01X1721445Y523128D02*
X1753311Y516354D01*
G01X1632213Y524438D02*
Y506963D01*
G01X1631063Y524317D02*
Y506963D01*
G01X1630832Y530937D02*
X1632213Y524438D01*
G01X1629751Y530489D02*
X1631063Y524317D01*
G01D02*
Y506963D01*
G01X1632213Y524438D02*
Y506963D01*
G01X1629751Y530489D02*
X1631063Y524317D01*
G01X1630832Y530937D02*
X1632213Y524438D01*
G01X1718764Y929555D02*
X1720253Y929738D01*
G01X1714595Y929044D02*
X1716084Y929227D01*
G01X1718764Y929555D02*
X1720253Y929738D01*
G01X1714595Y929044D02*
X1716084Y929227D01*
G01X1695968Y943573D02*
X1751671Y963543D01*
G01X1695688Y944695D02*
X1751471Y964693D01*
G01X1695688Y944695D02*
X1751471Y964693D01*
G01X1695968Y943573D02*
X1751671Y963543D01*
G01X1756425Y58021D02*
Y54275D01*
G01X1755275Y57900D02*
Y54275D01*
G01X1756175Y59198D02*
X1756425Y58021D01*
G01X1755073Y58850D02*
X1755275Y57900D01*
G01X1753490Y65523D02*
X1756175Y59198D01*
G01X1752568Y64749D02*
X1755073Y58850D01*
G01X1755275Y57900D02*
Y54275D01*
G01X1756425Y58021D02*
Y54275D01*
G01X1755073Y58850D02*
X1755275Y57900D01*
G01X1756175Y59198D02*
X1756425Y58021D01*
G01X1752568Y64749D02*
X1755073Y58850D01*
G01X1753490Y65523D02*
X1756175Y59198D01*
G01X1756425Y513669D02*
Y507075D01*
G01X1755275Y513328D02*
Y507075D01*
G01X1754017Y517381D02*
X1756425Y513669D01*
G01X1754293Y514842D02*
X1755275Y513328D01*
G01X1753311Y516354D02*
X1754293Y514842D01*
G01X1721893Y524209D02*
X1754017Y517381D01*
G01X1755275Y513328D02*
Y507075D01*
G01X1756425Y513669D02*
Y507075D01*
G01X1754293Y514842D02*
X1755275Y513328D01*
G01X1754017Y517381D02*
X1756425Y513669D01*
G01X1753311Y516354D02*
X1754293Y514842D01*
G01X1754017Y517381D02*
X1756425Y513669D01*
G01X1721893Y524209D02*
X1754017Y517381D01*
G01X1769021Y935717D02*
X1858139Y963536D01*
G01X1768774Y936846D02*
X1857963Y964686D01*
G01X1727102Y930577D02*
X1769021Y935717D01*
G01X1722933Y930066D02*
X1724422Y930249D01*
G01X1768774Y936846D02*
X1857963Y964686D01*
G01X1769021Y935717D02*
X1858139Y963536D01*
G01X1727102Y930577D02*
X1769021Y935717D01*
G01X1722933Y930066D02*
X1724422Y930249D01*
G01X1751671Y963543D02*
X1753827D01*
G01X1751471Y964693D02*
X1753803D01*
G01X1751471D02*
X1753803D01*
G01X1751671Y963543D02*
X1753827D01*
G01X1880638Y61900D02*
Y54262D01*
G01X1879488Y61524D02*
Y54288D01*
G01X1876786Y67175D02*
X1880638Y61900D01*
G01X1875957Y66358D02*
X1879488Y61524D01*
G01X1840251Y94664D02*
X1876786Y67175D01*
G01X1839763Y93592D02*
X1875957Y66358D01*
G01X1879488Y61524D02*
Y54288D01*
G01X1880638Y61900D02*
Y54262D01*
G01X1875957Y66358D02*
X1879488Y61524D01*
G01X1876786Y67175D02*
X1880638Y61900D01*
G01X1839763Y93592D02*
X1875957Y66358D01*
G01X1840251Y94664D02*
X1876786Y67175D01*
G01X1880638Y510989D02*
Y506988D01*
G01X1879488Y510648D02*
Y506988D01*
G01X1878788Y513835D02*
X1880638Y510989D01*
G01X1877957Y513003D02*
X1879488Y510648D01*
G01X1873153Y517494D02*
X1878788Y513835D01*
G01X1872705Y516413D02*
X1877957Y513003D01*
G01X1879488Y510648D02*
Y506988D01*
G01X1880638Y510989D02*
Y506988D01*
G01X1877957Y513003D02*
X1879488Y510648D01*
G01X1878788Y513835D02*
X1880638Y510989D01*
G01X1872705Y516413D02*
X1877957Y513003D01*
G01X1873153Y517494D02*
X1878788Y513835D01*
G01X1858139Y963536D02*
X1877896D01*
G01X1857963Y964686D02*
X1877896D01*
G01X1857963D02*
X1877896D01*
G01X1858139Y963536D02*
X1877896D01*
G54D12*
G01X6250Y-33194D02*
Y-50694D01*
G01X1228Y-33194D02*
X11272D01*
G01X20038Y-50694D02*
Y-33194D01*
G01Y-41652D02*
X21130Y-40194D01*
X22222Y-39319D01*
X23968Y-39028D01*
X25278Y-39319D01*
X26807Y-40486D01*
X27462Y-42236D01*
Y-50694D01*
G01X41250Y-39028D02*
Y-50694D01*
G01Y-34361D02*
X40813Y-34069D01*
Y-33486D01*
X41250Y-33194D01*
X41687Y-33486D01*
Y-34069D01*
X41250Y-34361D01*
G01X55475Y-48653D02*
X56567Y-49819D01*
X58095Y-50694D01*
X59405D01*
X60715Y-50111D01*
X61588Y-49236D01*
X62025Y-48070D01*
X61807Y-46319D01*
X60933Y-45444D01*
X57003Y-43694D01*
X56130Y-41652D01*
X56567Y-40194D01*
X57440Y-39319D01*
X58750Y-39028D01*
X60060Y-39319D01*
X61370Y-40194D01*
G01X90693Y-55069D02*
X92222Y-56236D01*
X93968Y-56527D01*
X95496Y-56236D01*
X96807Y-54778D01*
X97680Y-52736D01*
Y-39028D01*
G01Y-41361D02*
X96807Y-40194D01*
X95496Y-39319D01*
X93968Y-39028D01*
X92222Y-39611D01*
X91130Y-40777D01*
X90256Y-42819D01*
X89820Y-44861D01*
X90038Y-46611D01*
X90912Y-48653D01*
X92222Y-50111D01*
X93968Y-50694D01*
X95278Y-50402D01*
X96807Y-49236D01*
X97680Y-48070D01*
G01X107975Y-42819D02*
X114962D01*
X114307Y-40777D01*
X113215Y-39611D01*
X111687Y-39028D01*
X110158Y-39319D01*
X108848Y-40194D01*
X107975Y-42236D01*
X107538Y-43986D01*
Y-45736D01*
X107975Y-47486D01*
X109067Y-49236D01*
X110377Y-50402D01*
X111905Y-50694D01*
X113433Y-50111D01*
X114962Y-48361D01*
G01X125693Y-50694D02*
Y-39028D01*
G01Y-41361D02*
X126785Y-40194D01*
X127877Y-39319D01*
X129405Y-39028D01*
X130496Y-39319D01*
X131807Y-40194D01*
G01X142320Y-50694D02*
Y-33194D01*
G01Y-41944D02*
X143412Y-40194D01*
X144722Y-39319D01*
X146032Y-39028D01*
X147996Y-39611D01*
X149307Y-40777D01*
X150180Y-42819D01*
Y-45152D01*
X149743Y-47486D01*
X148870Y-49236D01*
X147342Y-50402D01*
X146032Y-50694D01*
X144722Y-50402D01*
X143412Y-49528D01*
X142320Y-48070D01*
G01X160475Y-42819D02*
X167462D01*
X166807Y-40777D01*
X165715Y-39611D01*
X164187Y-39028D01*
X162658Y-39319D01*
X161348Y-40194D01*
X160475Y-42236D01*
X160038Y-43986D01*
Y-45736D01*
X160475Y-47486D01*
X161567Y-49236D01*
X162877Y-50402D01*
X164405Y-50694D01*
X165933Y-50111D01*
X167462Y-48361D01*
G01X178193Y-50694D02*
Y-39028D01*
G01Y-41361D02*
X179285Y-40194D01*
X180377Y-39319D01*
X181905Y-39028D01*
X182996Y-39319D01*
X184307Y-40194D01*
G01X216250Y-39028D02*
Y-50694D01*
G01Y-34361D02*
X215813Y-34069D01*
Y-33486D01*
X216250Y-33194D01*
X216687Y-33486D01*
Y-34069D01*
X216250Y-34361D01*
G01X230475Y-48653D02*
X231567Y-49819D01*
X233095Y-50694D01*
X234405D01*
X235715Y-50111D01*
X236588Y-49236D01*
X237025Y-48070D01*
X236807Y-46319D01*
X235933Y-45444D01*
X232003Y-43694D01*
X231130Y-41652D01*
X231567Y-40194D01*
X232440Y-39319D01*
X233750Y-39028D01*
X235060Y-39319D01*
X236370Y-40194D01*
G01X265256Y-55069D02*
X266785Y-56236D01*
X268095Y-56527D01*
X269842Y-55944D01*
X271152Y-54486D01*
X271807Y-51860D01*
Y-39028D01*
G01Y-34361D02*
X271370Y-34069D01*
Y-33486D01*
X271807Y-33194D01*
X272243Y-33486D01*
Y-34069D01*
X271807Y-34361D01*
G01X282538Y-39028D02*
Y-47194D01*
X283412Y-49236D01*
X284722Y-50402D01*
X286250Y-50694D01*
X287778Y-50402D01*
X289088Y-49236D01*
X289962Y-47194D01*
G01Y-50694D02*
Y-39028D01*
G01X300475Y-48653D02*
X301567Y-49819D01*
X303095Y-50694D01*
X304405D01*
X305715Y-50111D01*
X306588Y-49236D01*
X307025Y-48070D01*
X306807Y-46319D01*
X305933Y-45444D01*
X302003Y-43694D01*
X301130Y-41652D01*
X301567Y-40194D01*
X302440Y-39319D01*
X303750Y-39028D01*
X305060Y-39319D01*
X306370Y-40194D01*
G01X321250Y-33194D02*
Y-50694D01*
G01X318193Y-39028D02*
X324307D01*
G01X354940Y-50694D02*
Y-35819D01*
X355377Y-34361D01*
X356250Y-33486D01*
X357560Y-33194D01*
X358870Y-33777D01*
X359525Y-35236D01*
G01X356905Y-40194D02*
X352538D01*
G01X373750Y-50694D02*
X372440Y-50402D01*
X371130Y-49236D01*
X370256Y-47194D01*
X369820Y-44861D01*
X370256Y-42527D01*
X371130Y-40486D01*
X372440Y-39319D01*
X373750Y-39028D01*
X375060Y-39319D01*
X376370Y-40486D01*
X377243Y-42527D01*
X377462Y-44861D01*
X377243Y-47194D01*
X376370Y-49236D01*
X375060Y-50402D01*
X373750Y-50694D01*
G01X388193D02*
Y-39028D01*
G01Y-41361D02*
X389285Y-40194D01*
X390377Y-39319D01*
X391905Y-39028D01*
X392996Y-39319D01*
X394307Y-40194D01*
G01X421665Y-55944D02*
X422975Y-56527D01*
X424722Y-55944D01*
X425813Y-54778D01*
X426687Y-53319D01*
X427996Y-48653D01*
X430835Y-39028D01*
G01X423848D02*
X427996Y-48653D01*
G01X443750Y-50694D02*
X442440Y-50402D01*
X441130Y-49236D01*
X440256Y-47194D01*
X439820Y-44861D01*
X440256Y-42527D01*
X441130Y-40486D01*
X442440Y-39319D01*
X443750Y-39028D01*
X445060Y-39319D01*
X446370Y-40486D01*
X447243Y-42527D01*
X447462Y-44861D01*
X447243Y-47194D01*
X446370Y-49236D01*
X445060Y-50402D01*
X443750Y-50694D01*
G01X457538Y-39028D02*
Y-47194D01*
X458412Y-49236D01*
X459722Y-50402D01*
X461250Y-50694D01*
X462778Y-50402D01*
X464088Y-49236D01*
X464962Y-47194D01*
G01Y-50694D02*
Y-39028D01*
G01X475693Y-50694D02*
Y-39028D01*
G01Y-41361D02*
X476785Y-40194D01*
X477877Y-39319D01*
X479405Y-39028D01*
X480496Y-39319D01*
X481807Y-40194D01*
G01X510693Y-50694D02*
Y-39028D01*
G01Y-41361D02*
X511785Y-40194D01*
X512877Y-39319D01*
X514405Y-39028D01*
X515496Y-39319D01*
X516807Y-40194D01*
G01X527975Y-42819D02*
X534962D01*
X534307Y-40777D01*
X533215Y-39611D01*
X531687Y-39028D01*
X530158Y-39319D01*
X528848Y-40194D01*
X527975Y-42236D01*
X527538Y-43986D01*
Y-45736D01*
X527975Y-47486D01*
X529067Y-49236D01*
X530377Y-50402D01*
X531905Y-50694D01*
X533433Y-50111D01*
X534962Y-48361D01*
G01X547440Y-50694D02*
Y-35819D01*
X547877Y-34361D01*
X548750Y-33486D01*
X550060Y-33194D01*
X551370Y-33777D01*
X552025Y-35236D01*
G01X549405Y-40194D02*
X545038D01*
G01X562975Y-42819D02*
X569962D01*
X569307Y-40777D01*
X568215Y-39611D01*
X566687Y-39028D01*
X565158Y-39319D01*
X563848Y-40194D01*
X562975Y-42236D01*
X562538Y-43986D01*
Y-45736D01*
X562975Y-47486D01*
X564067Y-49236D01*
X565377Y-50402D01*
X566905Y-50694D01*
X568433Y-50111D01*
X569962Y-48361D01*
G01X580693Y-50694D02*
Y-39028D01*
G01Y-41361D02*
X581785Y-40194D01*
X582877Y-39319D01*
X584405Y-39028D01*
X585496Y-39319D01*
X586807Y-40194D01*
G01X597975Y-42819D02*
X604962D01*
X604307Y-40777D01*
X603215Y-39611D01*
X601687Y-39028D01*
X600158Y-39319D01*
X598848Y-40194D01*
X597975Y-42236D01*
X597538Y-43986D01*
Y-45736D01*
X597975Y-47486D01*
X599067Y-49236D01*
X600377Y-50402D01*
X601905Y-50694D01*
X603433Y-50111D01*
X604962Y-48361D01*
G01X615038Y-50694D02*
Y-39028D01*
G01Y-41944D02*
X615912Y-40486D01*
X617222Y-39319D01*
X618968Y-39028D01*
X620496Y-39319D01*
X621807Y-40486D01*
X622462Y-42527D01*
Y-50694D01*
G01X639743Y-40486D02*
X638215Y-39319D01*
X636905Y-39028D01*
X635158Y-39611D01*
X633848Y-40777D01*
X632975Y-42819D01*
X632756Y-44861D01*
X632975Y-46903D01*
X633848Y-48653D01*
X635158Y-50111D01*
X636905Y-50694D01*
X638433Y-50111D01*
X639743Y-48944D01*
G01X650475Y-42819D02*
X657462D01*
X656807Y-40777D01*
X655715Y-39611D01*
X654187Y-39028D01*
X652658Y-39319D01*
X651348Y-40194D01*
X650475Y-42236D01*
X650038Y-43986D01*
Y-45736D01*
X650475Y-47486D01*
X651567Y-49236D01*
X652877Y-50402D01*
X654405Y-50694D01*
X655933Y-50111D01*
X657462Y-48361D01*
G01X688750Y-33194D02*
Y-50694D01*
G01X685693Y-39028D02*
X691807D01*
G01X706250Y-50694D02*
X704940Y-50402D01*
X703630Y-49236D01*
X702756Y-47194D01*
X702320Y-44861D01*
X702756Y-42527D01*
X703630Y-40486D01*
X704940Y-39319D01*
X706250Y-39028D01*
X707560Y-39319D01*
X708870Y-40486D01*
X709743Y-42527D01*
X709962Y-44861D01*
X709743Y-47194D01*
X708870Y-49236D01*
X707560Y-50402D01*
X706250Y-50694D01*
G01X739940D02*
Y-35819D01*
X740377Y-34361D01*
X741250Y-33486D01*
X742560Y-33194D01*
X743870Y-33777D01*
X744525Y-35236D01*
G01X741905Y-40194D02*
X737538D01*
G01X758750Y-39028D02*
Y-50694D01*
G01Y-34361D02*
X758313Y-34069D01*
Y-33486D01*
X758750Y-33194D01*
X759187Y-33486D01*
Y-34069D01*
X758750Y-34361D01*
G01X772538Y-50694D02*
Y-39028D01*
G01Y-41944D02*
X773412Y-40486D01*
X774722Y-39319D01*
X776468Y-39028D01*
X777996Y-39319D01*
X779307Y-40486D01*
X779962Y-42527D01*
Y-50694D01*
G01X797680Y-33194D02*
Y-50694D01*
G01Y-48070D02*
X796807Y-49528D01*
X795496Y-50402D01*
X793968Y-50694D01*
X792222Y-50111D01*
X790912Y-48653D01*
X790038Y-46903D01*
X789820Y-44861D01*
X790038Y-42819D01*
X790912Y-41069D01*
X792222Y-39611D01*
X793968Y-39028D01*
X795496Y-39319D01*
X796588Y-39903D01*
X797680Y-41069D01*
G01X828750Y-33194D02*
Y-50694D01*
G01X825693Y-39028D02*
X831807D01*
G01X842538Y-50694D02*
Y-33194D01*
G01Y-41652D02*
X843630Y-40194D01*
X844722Y-39319D01*
X846468Y-39028D01*
X847778Y-39319D01*
X849307Y-40486D01*
X849962Y-42236D01*
Y-50694D01*
G01X860475Y-42819D02*
X867462D01*
X866807Y-40777D01*
X865715Y-39611D01*
X864187Y-39028D01*
X862658Y-39319D01*
X861348Y-40194D01*
X860475Y-42236D01*
X860038Y-43986D01*
Y-45736D01*
X860475Y-47486D01*
X861567Y-49236D01*
X862877Y-50402D01*
X864405Y-50694D01*
X865933Y-50111D01*
X867462Y-48361D01*
G01X893947Y-50694D02*
Y-33194D01*
X898313D01*
X900060Y-34069D01*
X901370Y-35236D01*
X902462Y-36985D01*
X903335Y-39028D01*
X903553Y-41944D01*
X903335Y-44861D01*
X902462Y-46903D01*
X901370Y-48653D01*
X900060Y-49819D01*
X898313Y-50694D01*
X893947D01*
G01X911883D02*
Y-33194D01*
X917123D01*
X918870Y-34069D01*
X920180Y-36111D01*
X920617Y-38444D01*
X920180Y-40777D01*
X919088Y-42527D01*
X917123Y-43403D01*
X911883D01*
G01X951250Y-39028D02*
Y-50694D01*
G01Y-34361D02*
X950813Y-34069D01*
Y-33486D01*
X951250Y-33194D01*
X951687Y-33486D01*
Y-34069D01*
X951250Y-34361D01*
G01X962200Y-50694D02*
Y-39028D01*
G01Y-42236D02*
X962855Y-40777D01*
X963947Y-39611D01*
X965475Y-39028D01*
X967003Y-39611D01*
X968095Y-40777D01*
X968750Y-42236D01*
Y-50694D01*
G01Y-42236D02*
X969405Y-40777D01*
X970496Y-39611D01*
X972025Y-39028D01*
X973553Y-39611D01*
X974645Y-40777D01*
X975300Y-42527D01*
Y-50694D01*
G01X982320Y-56527D02*
Y-39028D01*
G01Y-41652D02*
X983412Y-40194D01*
X984503Y-39319D01*
X986250Y-39028D01*
X987778Y-39319D01*
X989307Y-40777D01*
X989962Y-42819D01*
X990180Y-44861D01*
X989962Y-46903D01*
X989307Y-48944D01*
X987996Y-50111D01*
X986250Y-50694D01*
X984722Y-50402D01*
X983193Y-49528D01*
X982320Y-48361D01*
G01X1000475Y-42819D02*
X1007462D01*
X1006807Y-40777D01*
X1005715Y-39611D01*
X1004187Y-39028D01*
X1002658Y-39319D01*
X1001348Y-40194D01*
X1000475Y-42236D01*
X1000038Y-43986D01*
Y-45736D01*
X1000475Y-47486D01*
X1001567Y-49236D01*
X1002877Y-50402D01*
X1004405Y-50694D01*
X1005933Y-50111D01*
X1007462Y-48361D01*
G01X1025180Y-33194D02*
Y-50694D01*
G01Y-48070D02*
X1024307Y-49528D01*
X1022996Y-50402D01*
X1021468Y-50694D01*
X1019722Y-50111D01*
X1018412Y-48653D01*
X1017538Y-46903D01*
X1017320Y-44861D01*
X1017538Y-42819D01*
X1018412Y-41069D01*
X1019722Y-39611D01*
X1021468Y-39028D01*
X1022996Y-39319D01*
X1024088Y-39903D01*
X1025180Y-41069D01*
G01X1042680Y-50694D02*
Y-39028D01*
G01Y-41069D02*
X1041807Y-39903D01*
X1040496Y-39319D01*
X1038968Y-39028D01*
X1037440Y-39611D01*
X1036130Y-40777D01*
X1035256Y-42527D01*
X1034820Y-44861D01*
X1035256Y-47194D01*
X1036130Y-48944D01*
X1037440Y-50111D01*
X1038968Y-50694D01*
X1040496Y-50402D01*
X1041807Y-49528D01*
X1042680Y-48361D01*
G01X1052538Y-50694D02*
Y-39028D01*
G01Y-41944D02*
X1053412Y-40486D01*
X1054722Y-39319D01*
X1056468Y-39028D01*
X1057996Y-39319D01*
X1059307Y-40486D01*
X1059962Y-42527D01*
Y-50694D01*
G01X1077243Y-40486D02*
X1075715Y-39319D01*
X1074405Y-39028D01*
X1072658Y-39611D01*
X1071348Y-40777D01*
X1070475Y-42819D01*
X1070256Y-44861D01*
X1070475Y-46903D01*
X1071348Y-48653D01*
X1072658Y-50111D01*
X1074405Y-50694D01*
X1075933Y-50111D01*
X1077243Y-48944D01*
G01X1087975Y-42819D02*
X1094962D01*
X1094307Y-40777D01*
X1093215Y-39611D01*
X1091687Y-39028D01*
X1090158Y-39319D01*
X1088848Y-40194D01*
X1087975Y-42236D01*
X1087538Y-43986D01*
Y-45736D01*
X1087975Y-47486D01*
X1089067Y-49236D01*
X1090377Y-50402D01*
X1091905Y-50694D01*
X1093433Y-50111D01*
X1094962Y-48361D01*
G01X1126250Y-33194D02*
Y-50694D01*
G01X1123193Y-39028D02*
X1129307D01*
G01X1140693Y-50694D02*
Y-39028D01*
G01Y-41361D02*
X1141785Y-40194D01*
X1142877Y-39319D01*
X1144405Y-39028D01*
X1145496Y-39319D01*
X1146807Y-40194D01*
G01X1165180Y-50694D02*
Y-39028D01*
G01Y-41069D02*
X1164307Y-39903D01*
X1162996Y-39319D01*
X1161468Y-39028D01*
X1159940Y-39611D01*
X1158630Y-40777D01*
X1157756Y-42527D01*
X1157320Y-44861D01*
X1157756Y-47194D01*
X1158630Y-48944D01*
X1159940Y-50111D01*
X1161468Y-50694D01*
X1162996Y-50402D01*
X1164307Y-49528D01*
X1165180Y-48361D01*
G01X1182243Y-40486D02*
X1180715Y-39319D01*
X1179405Y-39028D01*
X1177658Y-39611D01*
X1176348Y-40777D01*
X1175475Y-42819D01*
X1175256Y-44861D01*
X1175475Y-46903D01*
X1176348Y-48653D01*
X1177658Y-50111D01*
X1179405Y-50694D01*
X1180933Y-50111D01*
X1182243Y-48944D01*
G01X1192975Y-42819D02*
X1199962D01*
X1199307Y-40777D01*
X1198215Y-39611D01*
X1196687Y-39028D01*
X1195158Y-39319D01*
X1193848Y-40194D01*
X1192975Y-42236D01*
X1192538Y-43986D01*
Y-45736D01*
X1192975Y-47486D01*
X1194067Y-49236D01*
X1195377Y-50402D01*
X1196905Y-50694D01*
X1198433Y-50111D01*
X1199962Y-48361D01*
G01X1210475Y-48653D02*
X1211567Y-49819D01*
X1213095Y-50694D01*
X1214405D01*
X1215715Y-50111D01*
X1216588Y-49236D01*
X1217025Y-48070D01*
X1216807Y-46319D01*
X1215933Y-45444D01*
X1212003Y-43694D01*
X1211130Y-41652D01*
X1211567Y-40194D01*
X1212440Y-39319D01*
X1213750Y-39028D01*
X1215060Y-39319D01*
X1216370Y-40194D01*
G01X1248750Y-39028D02*
Y-50694D01*
G01Y-34361D02*
X1248313Y-34069D01*
Y-33486D01*
X1248750Y-33194D01*
X1249187Y-33486D01*
Y-34069D01*
X1248750Y-34361D01*
G01X1262538Y-50694D02*
Y-39028D01*
G01Y-41944D02*
X1263412Y-40486D01*
X1264722Y-39319D01*
X1266468Y-39028D01*
X1267996Y-39319D01*
X1269307Y-40486D01*
X1269962Y-42527D01*
Y-50694D01*
G01X1301250D02*
Y-33194D01*
G01X1322680Y-50694D02*
Y-39028D01*
G01Y-41069D02*
X1321807Y-39903D01*
X1320496Y-39319D01*
X1318968Y-39028D01*
X1317440Y-39611D01*
X1316130Y-40777D01*
X1315256Y-42527D01*
X1314820Y-44861D01*
X1315256Y-47194D01*
X1316130Y-48944D01*
X1317440Y-50111D01*
X1318968Y-50694D01*
X1320496Y-50402D01*
X1321807Y-49528D01*
X1322680Y-48361D01*
G01X1331665Y-55944D02*
X1332975Y-56527D01*
X1334722Y-55944D01*
X1335813Y-54778D01*
X1336687Y-53319D01*
X1337996Y-48653D01*
X1340835Y-39028D01*
G01X1333848D02*
X1337996Y-48653D01*
G01X1350475Y-42819D02*
X1357462D01*
X1356807Y-40777D01*
X1355715Y-39611D01*
X1354187Y-39028D01*
X1352658Y-39319D01*
X1351348Y-40194D01*
X1350475Y-42236D01*
X1350038Y-43986D01*
Y-45736D01*
X1350475Y-47486D01*
X1351567Y-49236D01*
X1352877Y-50402D01*
X1354405Y-50694D01*
X1355933Y-50111D01*
X1357462Y-48361D01*
G01X1368193Y-50694D02*
Y-39028D01*
G01Y-41361D02*
X1369285Y-40194D01*
X1370377Y-39319D01*
X1371905Y-39028D01*
X1372996Y-39319D01*
X1374307Y-40194D01*
G01X1401883Y-33194D02*
Y-50694D01*
X1410617D01*
G01X1423750D02*
X1425278Y-50402D01*
X1427025Y-49528D01*
X1428117Y-48070D01*
X1428553Y-46027D01*
X1428117Y-43986D01*
X1426807Y-42236D01*
X1424842Y-41361D01*
X1422658D01*
X1421348Y-40777D01*
X1420256Y-39319D01*
X1419820Y-37278D01*
X1420475Y-35236D01*
X1422003Y-33777D01*
X1423750Y-33194D01*
X1425496Y-33777D01*
X1427025Y-35236D01*
X1427680Y-37278D01*
X1427243Y-39319D01*
X1426152Y-40777D01*
X1424842Y-41361D01*
X1422658D01*
X1420693Y-42236D01*
X1419383Y-43986D01*
X1418947Y-46027D01*
X1419383Y-48070D01*
X1420475Y-49528D01*
X1422222Y-50402D01*
X1423750Y-50694D01*
G01X1441250Y-51277D02*
X1440813Y-50986D01*
Y-50402D01*
X1441250Y-50111D01*
X1441687Y-50402D01*
Y-50986D01*
X1441250Y-51277D01*
G01X1986890Y1495085D02*
Y1512585D01*
X1991256D01*
X1993003Y1511710D01*
X1994313Y1510543D01*
X1995405Y1508794D01*
X1996278Y1506751D01*
X1996496Y1503835D01*
X1996278Y1500918D01*
X1995405Y1498876D01*
X1994313Y1497126D01*
X1993003Y1495960D01*
X1991256Y1495085D01*
X1986890D01*
G01X2004826D02*
Y1512585D01*
X2010066D01*
X2011813Y1511710D01*
X2013123Y1509668D01*
X2013560Y1507335D01*
X2013123Y1505002D01*
X2012031Y1503252D01*
X2010066Y1502376D01*
X2004826D01*
G01X2041573Y1512585D02*
X2046813D01*
G01X2044193D02*
Y1495085D01*
G01X2041573D02*
X2046813D01*
G01X2056016D02*
Y1512585D01*
X2061693Y1498002D01*
X2067370Y1512585D01*
Y1495085D01*
G01X2074826D02*
Y1512585D01*
X2080066D01*
X2081813Y1511710D01*
X2083123Y1509668D01*
X2083560Y1507335D01*
X2083123Y1505002D01*
X2082031Y1503252D01*
X2080066Y1502376D01*
X2074826D01*
G01X2101060Y1495085D02*
X2092326D01*
Y1512585D01*
X2101060D01*
G01X2097566Y1504127D02*
X2092326D01*
G01X2109390Y1495085D02*
Y1512585D01*
X2113756D01*
X2115503Y1511710D01*
X2116813Y1510543D01*
X2117905Y1508794D01*
X2118778Y1506751D01*
X2118996Y1503835D01*
X2118778Y1500918D01*
X2117905Y1498876D01*
X2116813Y1497126D01*
X2115503Y1495960D01*
X2113756Y1495085D01*
X2109390D01*
G01X2126234D02*
X2131693Y1512585D01*
X2137152Y1495085D01*
G01X2135186Y1501210D02*
X2128199D01*
G01X2144171Y1495085D02*
Y1512585D01*
X2154215Y1495085D01*
Y1512585D01*
G01X2171496Y1511126D02*
X2170186Y1512002D01*
X2168658Y1512585D01*
X2166911D01*
X2164946Y1511710D01*
X2163418Y1510252D01*
X2162326Y1508501D01*
X2161453Y1505585D01*
X2161234Y1502960D01*
X2161671Y1500335D01*
X2162326Y1498585D01*
X2163636Y1496835D01*
X2165165Y1495668D01*
X2166693Y1495085D01*
X2168221D01*
X2169750Y1495668D01*
X2171060Y1496543D01*
X2172152Y1497709D01*
G01X2188560Y1495085D02*
X2179826D01*
Y1512585D01*
X2188560D01*
G01X2185066Y1504127D02*
X2179826D01*
G01X2219193Y1512585D02*
Y1495085D01*
G01X2214171Y1512585D02*
X2224215D01*
G01X2231234Y1495085D02*
X2236693Y1512585D01*
X2242152Y1495085D01*
G01X2240186Y1501210D02*
X2233199D01*
G01X2255939Y1504418D02*
X2256813Y1505293D01*
X2257468Y1506751D01*
X2257905Y1508794D01*
X2257468Y1510543D01*
X2256595Y1511710D01*
X2255066Y1512585D01*
X2249171D01*
Y1495085D01*
X2256376D01*
X2257905Y1496251D01*
X2258778Y1498002D01*
X2259215Y1500043D01*
X2258778Y1502085D01*
X2257468Y1503835D01*
X2255939Y1504418D01*
X2249171D01*
G01X2267326Y1512585D02*
Y1495085D01*
X2276060D01*
G01X2293560D02*
X2284826D01*
Y1512585D01*
X2293560D01*
G01X2290066Y1504127D02*
X2284826D01*
G01X2306693Y1494502D02*
X2306256Y1494793D01*
Y1495377D01*
X2306693Y1495668D01*
X2307130Y1495377D01*
Y1494793D01*
X2306693Y1494502D01*
G01Y1502376D02*
X2306256Y1502668D01*
Y1503252D01*
X2306693Y1503543D01*
X2307130Y1503252D01*
Y1502668D01*
X2306693Y1502376D01*
G01X2337326Y1512585D02*
Y1495085D01*
X2346060D01*
G01X2359193D02*
X2360721Y1495377D01*
X2362468Y1496251D01*
X2363560Y1497709D01*
X2363996Y1499752D01*
X2363560Y1501793D01*
X2362250Y1503543D01*
X2360285Y1504418D01*
X2358101D01*
X2356791Y1505002D01*
X2355699Y1506460D01*
X2355263Y1508501D01*
X2355918Y1510543D01*
X2357446Y1512002D01*
X2359193Y1512585D01*
X2360939Y1512002D01*
X2362468Y1510543D01*
X2363123Y1508501D01*
X2362686Y1506460D01*
X2361595Y1505002D01*
X2360285Y1504418D01*
X2358101D01*
X2356136Y1503543D01*
X2354826Y1501793D01*
X2354390Y1499752D01*
X2354826Y1497709D01*
X2355918Y1496251D01*
X2357665Y1495377D01*
X2359193Y1495085D01*
G01X2008773Y1477935D02*
X2014013D01*
G01X2011393D02*
Y1460435D01*
G01X2008773D02*
X2014013D01*
G01X2023216D02*
Y1477935D01*
X2028893Y1463352D01*
X2034570Y1477935D01*
Y1460435D01*
G01X2042026D02*
Y1477935D01*
X2047266D01*
X2049013Y1477060D01*
X2050323Y1475018D01*
X2050760Y1472685D01*
X2050323Y1470352D01*
X2049231Y1468602D01*
X2047266Y1467726D01*
X2042026D01*
G01X2062801Y1454602D02*
X2060618Y1457518D01*
X2059526Y1460435D01*
Y1472101D01*
X2060618Y1475018D01*
X2062801Y1477935D01*
G01X2081393Y1460435D02*
X2079646Y1460727D01*
X2078118Y1461893D01*
X2076808Y1463643D01*
X2075934Y1465685D01*
X2075498Y1468018D01*
Y1470352D01*
X2075934Y1472685D01*
X2076808Y1474727D01*
X2078118Y1476476D01*
X2079646Y1477643D01*
X2081393Y1477935D01*
X2083139Y1477643D01*
X2084668Y1476476D01*
X2085978Y1474727D01*
X2086852Y1472685D01*
X2087288Y1470352D01*
Y1468018D01*
X2086852Y1465685D01*
X2085978Y1463643D01*
X2084668Y1461893D01*
X2083139Y1460727D01*
X2081393Y1460435D01*
G01X2095181D02*
Y1477935D01*
G01Y1469477D02*
X2096273Y1470935D01*
X2097365Y1471810D01*
X2099111Y1472101D01*
X2100421Y1471810D01*
X2101950Y1470643D01*
X2102605Y1468893D01*
Y1460435D01*
G01X2109843D02*
Y1472101D01*
G01Y1468893D02*
X2110498Y1470352D01*
X2111590Y1471518D01*
X2113118Y1472101D01*
X2114646Y1471518D01*
X2115738Y1470352D01*
X2116393Y1468893D01*
Y1460435D01*
G01Y1468893D02*
X2117048Y1470352D01*
X2118139Y1471518D01*
X2119668Y1472101D01*
X2121196Y1471518D01*
X2122288Y1470352D01*
X2122943Y1468602D01*
Y1460435D01*
G01X2134985Y1454602D02*
X2137168Y1457518D01*
X2138260Y1460435D01*
Y1472101D01*
X2137168Y1475018D01*
X2134985Y1477935D01*
G01X2046393Y1425785D02*
X2047921Y1426077D01*
X2049668Y1426951D01*
X2050760Y1428409D01*
X2051196Y1430452D01*
X2050760Y1432493D01*
X2049450Y1434243D01*
X2047485Y1435118D01*
X2045301D01*
X2043991Y1435702D01*
X2042899Y1437160D01*
X2042463Y1439201D01*
X2043118Y1441243D01*
X2044646Y1442702D01*
X2046393Y1443285D01*
X2048139Y1442702D01*
X2049668Y1441243D01*
X2050323Y1439201D01*
X2049886Y1437160D01*
X2048795Y1435702D01*
X2047485Y1435118D01*
X2045301D01*
X2043336Y1434243D01*
X2042026Y1432493D01*
X2041590Y1430452D01*
X2042026Y1428409D01*
X2043118Y1426951D01*
X2044865Y1426077D01*
X2046393Y1425785D01*
G01X2059090Y1428409D02*
X2060399Y1426951D01*
X2061928Y1426077D01*
X2063893Y1425785D01*
X2065858Y1426368D01*
X2067386Y1427535D01*
X2068478Y1429576D01*
X2068696Y1431910D01*
X2068260Y1434243D01*
X2067168Y1435702D01*
X2065639Y1436868D01*
X2064111Y1437160D01*
X2062583Y1436868D01*
X2060618Y1435702D01*
X2061273Y1443285D01*
X2067168D01*
G01X2081393Y1425202D02*
X2080956Y1425493D01*
Y1426077D01*
X2081393Y1426368D01*
X2081830Y1426077D01*
Y1425493D01*
X2081393Y1425202D01*
G01X2098893Y1443285D02*
X2097146Y1442702D01*
X2095836Y1441243D01*
X2094963Y1439494D01*
X2094308Y1437160D01*
X2094090Y1434535D01*
X2094308Y1431910D01*
X2094963Y1429576D01*
X2095836Y1427826D01*
X2097146Y1426368D01*
X2098893Y1425785D01*
X2100639Y1426368D01*
X2101950Y1427826D01*
X2102823Y1429576D01*
X2103478Y1431910D01*
X2103696Y1434535D01*
X2103478Y1437160D01*
X2102823Y1439494D01*
X2101950Y1441243D01*
X2100639Y1442702D01*
X2098893Y1443285D01*
G01X2037643Y1391135D02*
Y1408635D01*
X2035023Y1405135D01*
G01Y1391135D02*
X2040263D01*
G01X2055143Y1408635D02*
X2053396Y1408052D01*
X2052086Y1406593D01*
X2051213Y1404844D01*
X2050558Y1402510D01*
X2050340Y1399885D01*
X2050558Y1397260D01*
X2051213Y1394926D01*
X2052086Y1393176D01*
X2053396Y1391718D01*
X2055143Y1391135D01*
X2056889Y1391718D01*
X2058200Y1393176D01*
X2059073Y1394926D01*
X2059728Y1397260D01*
X2059946Y1399885D01*
X2059728Y1402510D01*
X2059073Y1404844D01*
X2058200Y1406593D01*
X2056889Y1408052D01*
X2055143Y1408635D01*
G01X2072643D02*
X2070896Y1408052D01*
X2069586Y1406593D01*
X2068713Y1404844D01*
X2068058Y1402510D01*
X2067840Y1399885D01*
X2068058Y1397260D01*
X2068713Y1394926D01*
X2069586Y1393176D01*
X2070896Y1391718D01*
X2072643Y1391135D01*
X2074389Y1391718D01*
X2075700Y1393176D01*
X2076573Y1394926D01*
X2077228Y1397260D01*
X2077446Y1399885D01*
X2077228Y1402510D01*
X2076573Y1404844D01*
X2075700Y1406593D01*
X2074389Y1408052D01*
X2072643Y1408635D01*
G01X2090143Y1390552D02*
X2089706Y1390843D01*
Y1391427D01*
X2090143Y1391718D01*
X2090580Y1391427D01*
Y1390843D01*
X2090143Y1390552D01*
G01X2107643Y1408635D02*
X2105896Y1408052D01*
X2104586Y1406593D01*
X2103713Y1404844D01*
X2103058Y1402510D01*
X2102840Y1399885D01*
X2103058Y1397260D01*
X2103713Y1394926D01*
X2104586Y1393176D01*
X2105896Y1391718D01*
X2107643Y1391135D01*
X2109389Y1391718D01*
X2110700Y1393176D01*
X2111573Y1394926D01*
X2112228Y1397260D01*
X2112446Y1399885D01*
X2112228Y1402510D01*
X2111573Y1404844D01*
X2110700Y1406593D01*
X2109389Y1408052D01*
X2107643Y1408635D01*
G01X2188593Y1477935D02*
X2191649Y1460435D01*
X2195143Y1477935D01*
X2198636Y1460435D01*
X2201693Y1477935D01*
G01X2210023D02*
X2215263D01*
G01X2212643D02*
Y1460435D01*
G01X2210023D02*
X2215263D01*
G01X2225340D02*
Y1477935D01*
X2229706D01*
X2231453Y1477060D01*
X2232763Y1475893D01*
X2233855Y1474144D01*
X2234728Y1472101D01*
X2234946Y1469185D01*
X2234728Y1466268D01*
X2233855Y1464226D01*
X2232763Y1462476D01*
X2231453Y1461310D01*
X2229706Y1460435D01*
X2225340D01*
G01X2247643Y1477935D02*
Y1460435D01*
G01X2242621Y1477935D02*
X2252665D01*
G01X2260558Y1460435D02*
Y1477935D01*
G01X2269728D02*
Y1460435D01*
G01Y1469185D02*
X2260558D01*
G01X2281551Y1454602D02*
X2279368Y1457518D01*
X2278276Y1460435D01*
Y1472101D01*
X2279368Y1475018D01*
X2281551Y1477935D01*
G01X2293593Y1460435D02*
Y1472101D01*
G01Y1468893D02*
X2294248Y1470352D01*
X2295340Y1471518D01*
X2296868Y1472101D01*
X2298396Y1471518D01*
X2299488Y1470352D01*
X2300143Y1468893D01*
Y1460435D01*
G01Y1468893D02*
X2300798Y1470352D01*
X2301889Y1471518D01*
X2303418Y1472101D01*
X2304946Y1471518D01*
X2306038Y1470352D01*
X2306693Y1468602D01*
Y1460435D01*
G01X2317643Y1472101D02*
Y1460435D01*
G01Y1476768D02*
X2317206Y1477060D01*
Y1477643D01*
X2317643Y1477935D01*
X2318080Y1477643D01*
Y1477060D01*
X2317643Y1476768D01*
G01X2335143Y1460435D02*
Y1477935D01*
G01X2349368Y1462476D02*
X2350460Y1461310D01*
X2351988Y1460435D01*
X2353298D01*
X2354608Y1461018D01*
X2355481Y1461893D01*
X2355918Y1463059D01*
X2355700Y1464810D01*
X2354826Y1465685D01*
X2350896Y1467435D01*
X2350023Y1469477D01*
X2350460Y1470935D01*
X2351333Y1471810D01*
X2352643Y1472101D01*
X2353953Y1471810D01*
X2355263Y1470935D01*
G01X2371235Y1454602D02*
X2373418Y1457518D01*
X2374510Y1460435D01*
Y1472101D01*
X2373418Y1475018D01*
X2371235Y1477935D01*
G01X2225995Y1433076D02*
X2227523Y1435118D01*
X2228833Y1436285D01*
X2230580Y1436868D01*
X2232108Y1436285D01*
X2233200Y1435118D01*
X2234073Y1433368D01*
X2234291Y1431327D01*
X2234073Y1429576D01*
X2233200Y1427826D01*
X2231889Y1426368D01*
X2230361Y1425785D01*
X2228615Y1426368D01*
X2227086Y1428118D01*
X2226213Y1430743D01*
X2225995Y1433660D01*
X2226431Y1437451D01*
X2227086Y1439494D01*
X2228178Y1441535D01*
X2229706Y1442993D01*
X2231235Y1443285D01*
X2232763Y1442702D01*
X2233855Y1441243D01*
G01X2247643Y1425202D02*
X2247206Y1425493D01*
Y1426077D01*
X2247643Y1426368D01*
X2248080Y1426077D01*
Y1425493D01*
X2247643Y1425202D01*
G01X2260340Y1428409D02*
X2261649Y1426951D01*
X2263178Y1426077D01*
X2265143Y1425785D01*
X2267108Y1426368D01*
X2268636Y1427535D01*
X2269728Y1429576D01*
X2269946Y1431910D01*
X2269510Y1434243D01*
X2268418Y1435702D01*
X2266889Y1436868D01*
X2265361Y1437160D01*
X2263833Y1436868D01*
X2261868Y1435702D01*
X2262523Y1443285D01*
X2268418D01*
G01X2278713Y1425202D02*
X2286573Y1443285D01*
G01X2295340Y1428409D02*
X2296649Y1426951D01*
X2298178Y1426077D01*
X2300143Y1425785D01*
X2302108Y1426368D01*
X2303636Y1427535D01*
X2304728Y1429576D01*
X2304946Y1431910D01*
X2304510Y1434243D01*
X2303418Y1435702D01*
X2301889Y1436868D01*
X2300361Y1437160D01*
X2298833Y1436868D01*
X2296868Y1435702D01*
X2297523Y1443285D01*
X2303418D01*
G01X2317643Y1425202D02*
X2317206Y1425493D01*
Y1426077D01*
X2317643Y1426368D01*
X2318080Y1426077D01*
Y1425493D01*
X2317643Y1425202D01*
G01X2335143Y1443285D02*
X2333396Y1442702D01*
X2332086Y1441243D01*
X2331213Y1439494D01*
X2330558Y1437160D01*
X2330340Y1434535D01*
X2330558Y1431910D01*
X2331213Y1429576D01*
X2332086Y1427826D01*
X2333396Y1426368D01*
X2335143Y1425785D01*
X2336889Y1426368D01*
X2338200Y1427826D01*
X2339073Y1429576D01*
X2339728Y1431910D01*
X2339946Y1434535D01*
X2339728Y1437160D01*
X2339073Y1439494D01*
X2338200Y1441243D01*
X2336889Y1442702D01*
X2335143Y1443285D01*
G01X2225340Y1393759D02*
X2226649Y1392301D01*
X2228178Y1391427D01*
X2230143Y1391135D01*
X2232108Y1391718D01*
X2233636Y1392885D01*
X2234728Y1394926D01*
X2234946Y1397260D01*
X2234510Y1399593D01*
X2233418Y1401052D01*
X2231889Y1402218D01*
X2230361Y1402510D01*
X2228833Y1402218D01*
X2226868Y1401052D01*
X2227523Y1408635D01*
X2233418D01*
G01X2247643Y1390552D02*
X2247206Y1390843D01*
Y1391427D01*
X2247643Y1391718D01*
X2248080Y1391427D01*
Y1390843D01*
X2247643Y1390552D01*
G01X2265143Y1408635D02*
X2263396Y1408052D01*
X2262086Y1406593D01*
X2261213Y1404844D01*
X2260558Y1402510D01*
X2260340Y1399885D01*
X2260558Y1397260D01*
X2261213Y1394926D01*
X2262086Y1393176D01*
X2263396Y1391718D01*
X2265143Y1391135D01*
X2266889Y1391718D01*
X2268200Y1393176D01*
X2269073Y1394926D01*
X2269728Y1397260D01*
X2269946Y1399885D01*
X2269728Y1402510D01*
X2269073Y1404844D01*
X2268200Y1406593D01*
X2266889Y1408052D01*
X2265143Y1408635D01*
G01X2278713Y1390552D02*
X2286573Y1408635D01*
G01X2295995Y1398426D02*
X2297523Y1400468D01*
X2298833Y1401635D01*
X2300580Y1402218D01*
X2302108Y1401635D01*
X2303200Y1400468D01*
X2304073Y1398718D01*
X2304291Y1396677D01*
X2304073Y1394926D01*
X2303200Y1393176D01*
X2301889Y1391718D01*
X2300361Y1391135D01*
X2298615Y1391718D01*
X2297086Y1393468D01*
X2296213Y1396093D01*
X2295995Y1399010D01*
X2296431Y1402801D01*
X2297086Y1404844D01*
X2298178Y1406885D01*
X2299706Y1408343D01*
X2301235Y1408635D01*
X2302763Y1408052D01*
X2303855Y1406593D01*
G01X2317643Y1390552D02*
X2317206Y1390843D01*
Y1391427D01*
X2317643Y1391718D01*
X2318080Y1391427D01*
Y1390843D01*
X2317643Y1390552D01*
G01X2330340Y1393759D02*
X2331649Y1392301D01*
X2333178Y1391427D01*
X2335143Y1391135D01*
X2337108Y1391718D01*
X2338636Y1392885D01*
X2339728Y1394926D01*
X2339946Y1397260D01*
X2339510Y1399593D01*
X2338418Y1401052D01*
X2336889Y1402218D01*
X2335361Y1402510D01*
X2333833Y1402218D01*
X2331868Y1401052D01*
X2332523Y1408635D01*
X2338418D01*
G01X2444090Y1425785D02*
Y1443285D01*
X2448456D01*
X2450203Y1442410D01*
X2451513Y1441243D01*
X2452605Y1439494D01*
X2453478Y1437451D01*
X2453696Y1434535D01*
X2453478Y1431618D01*
X2452605Y1429576D01*
X2451513Y1427826D01*
X2450203Y1426660D01*
X2448456Y1425785D01*
X2444090D01*
G01X2462026D02*
Y1443285D01*
X2467266D01*
X2469013Y1442410D01*
X2470323Y1440368D01*
X2470760Y1438035D01*
X2470323Y1435702D01*
X2469231Y1433952D01*
X2467266Y1433076D01*
X2462026D01*
G01X2444090Y1391135D02*
Y1408635D01*
X2448456D01*
X2450203Y1407760D01*
X2451513Y1406593D01*
X2452605Y1404844D01*
X2453478Y1402801D01*
X2453696Y1399885D01*
X2453478Y1396968D01*
X2452605Y1394926D01*
X2451513Y1393176D01*
X2450203Y1392010D01*
X2448456Y1391135D01*
X2444090D01*
G01X2462026D02*
Y1408635D01*
X2467266D01*
X2469013Y1407760D01*
X2470323Y1405718D01*
X2470760Y1403385D01*
X2470323Y1401052D01*
X2469231Y1399302D01*
X2467266Y1398426D01*
X2462026D01*
G01X2431393Y1477935D02*
Y1460435D01*
G01X2426371Y1477935D02*
X2436415D01*
G01X2448893Y1460435D02*
Y1468310D01*
X2444526Y1477935D01*
G01X2453260D02*
X2448893Y1468310D01*
G01X2462026Y1460435D02*
Y1477935D01*
X2467266D01*
X2469013Y1477060D01*
X2470323Y1475018D01*
X2470760Y1472685D01*
X2470323Y1470352D01*
X2469231Y1468602D01*
X2467266Y1467726D01*
X2462026D01*
G01X2488260Y1460435D02*
X2479526D01*
Y1477935D01*
X2488260D01*
G01X2484766Y1469477D02*
X2479526D01*
G01X2532026Y1460435D02*
Y1477935D01*
X2537485D01*
X2539231Y1477060D01*
X2540323Y1475893D01*
X2540760Y1473560D01*
X2540323Y1471226D01*
X2539013Y1469768D01*
X2537485Y1468893D01*
X2532026D01*
G01X2537485D02*
X2540760Y1460435D01*
G01X2550618Y1468310D02*
X2557605D01*
X2556950Y1470352D01*
X2555858Y1471518D01*
X2554330Y1472101D01*
X2552801Y1471810D01*
X2551491Y1470935D01*
X2550618Y1468893D01*
X2550181Y1467143D01*
Y1465393D01*
X2550618Y1463643D01*
X2551710Y1461893D01*
X2553020Y1460727D01*
X2554548Y1460435D01*
X2556076Y1461018D01*
X2557605Y1462768D01*
G01X2570083Y1460435D02*
Y1475310D01*
X2570520Y1476768D01*
X2571393Y1477643D01*
X2572703Y1477935D01*
X2574013Y1477352D01*
X2574668Y1475893D01*
G01X2572048Y1470935D02*
X2567681D01*
G01X2588893Y1459852D02*
X2588456Y1460143D01*
Y1460727D01*
X2588893Y1461018D01*
X2589330Y1460727D01*
Y1460143D01*
X2588893Y1459852D01*
G01X2619526Y1460435D02*
Y1477935D01*
X2624766D01*
X2626513Y1477060D01*
X2627823Y1475018D01*
X2628260Y1472685D01*
X2627823Y1470352D01*
X2626731Y1468602D01*
X2624766Y1467726D01*
X2619526D01*
G01X2641393Y1460435D02*
Y1477935D01*
G01X2662823Y1460435D02*
Y1472101D01*
G01Y1470060D02*
X2661950Y1471226D01*
X2660639Y1471810D01*
X2659111Y1472101D01*
X2657583Y1471518D01*
X2656273Y1470352D01*
X2655399Y1468602D01*
X2654963Y1466268D01*
X2655399Y1463935D01*
X2656273Y1462185D01*
X2657583Y1461018D01*
X2659111Y1460435D01*
X2660639Y1460727D01*
X2661950Y1461601D01*
X2662823Y1462768D01*
G01X2672681Y1460435D02*
Y1472101D01*
G01Y1469185D02*
X2673555Y1470643D01*
X2674865Y1471810D01*
X2676611Y1472101D01*
X2678139Y1471810D01*
X2679450Y1470643D01*
X2680105Y1468602D01*
Y1460435D01*
G01X2690618Y1468310D02*
X2697605D01*
X2696950Y1470352D01*
X2695858Y1471518D01*
X2694330Y1472101D01*
X2692801Y1471810D01*
X2691491Y1470935D01*
X2690618Y1468893D01*
X2690181Y1467143D01*
Y1465393D01*
X2690618Y1463643D01*
X2691710Y1461893D01*
X2693020Y1460727D01*
X2694548Y1460435D01*
X2696076Y1461018D01*
X2697605Y1462768D01*
G01X2602026Y1443285D02*
Y1425785D01*
X2610760D01*
G01X2623456D02*
X2623893Y1429576D01*
X2624548Y1432785D01*
X2625421Y1435702D01*
X2626513Y1438910D01*
X2628260Y1443285D01*
X2619526D01*
G01X2602026Y1408635D02*
Y1391135D01*
X2610760D01*
G01X2623456D02*
X2623893Y1394926D01*
X2624548Y1398135D01*
X2625421Y1401052D01*
X2626513Y1404260D01*
X2628260Y1408635D01*
X2619526D01*
G01X2811693Y1437451D02*
Y1425785D01*
G01Y1442118D02*
X2811256Y1442410D01*
Y1442993D01*
X2811693Y1443285D01*
X2812130Y1442993D01*
Y1442410D01*
X2811693Y1442118D01*
G01X2825918Y1427826D02*
X2827010Y1426660D01*
X2828538Y1425785D01*
X2829848D01*
X2831158Y1426368D01*
X2832031Y1427243D01*
X2832468Y1428409D01*
X2832250Y1430160D01*
X2831376Y1431035D01*
X2827446Y1432785D01*
X2826573Y1434827D01*
X2827010Y1436285D01*
X2827883Y1437160D01*
X2829193Y1437451D01*
X2830503Y1437160D01*
X2831813Y1436285D01*
G01X2859171Y1425785D02*
Y1443285D01*
X2869215Y1425785D01*
Y1443285D01*
G01X2881693Y1425785D02*
X2879946Y1426077D01*
X2878418Y1427243D01*
X2877108Y1428993D01*
X2876234Y1431035D01*
X2875798Y1433368D01*
Y1435702D01*
X2876234Y1438035D01*
X2877108Y1440077D01*
X2878418Y1441826D01*
X2879946Y1442993D01*
X2881693Y1443285D01*
X2883439Y1442993D01*
X2884968Y1441826D01*
X2886278Y1440077D01*
X2887152Y1438035D01*
X2887588Y1435702D01*
Y1433368D01*
X2887152Y1431035D01*
X2886278Y1428993D01*
X2884968Y1427243D01*
X2883439Y1426077D01*
X2881693Y1425785D01*
G01X2899193Y1443285D02*
Y1425785D01*
G01X2894171Y1443285D02*
X2904215D01*
G01X2930481Y1437451D02*
Y1429285D01*
X2931355Y1427243D01*
X2932665Y1426077D01*
X2934193Y1425785D01*
X2935721Y1426077D01*
X2937031Y1427243D01*
X2937905Y1429285D01*
G01Y1425785D02*
Y1437451D01*
G01X2948418Y1427826D02*
X2949510Y1426660D01*
X2951038Y1425785D01*
X2952348D01*
X2953658Y1426368D01*
X2954531Y1427243D01*
X2954968Y1428409D01*
X2954750Y1430160D01*
X2953876Y1431035D01*
X2949946Y1432785D01*
X2949073Y1434827D01*
X2949510Y1436285D01*
X2950383Y1437160D01*
X2951693Y1437451D01*
X2953003Y1437160D01*
X2954313Y1436285D01*
G01X2965918Y1433660D02*
X2972905D01*
X2972250Y1435702D01*
X2971158Y1436868D01*
X2969630Y1437451D01*
X2968101Y1437160D01*
X2966791Y1436285D01*
X2965918Y1434243D01*
X2965481Y1432493D01*
Y1430743D01*
X2965918Y1428993D01*
X2967010Y1427243D01*
X2968320Y1426077D01*
X2969848Y1425785D01*
X2971376Y1426368D01*
X2972905Y1428118D01*
G01X2990623Y1443285D02*
Y1425785D01*
G01Y1428409D02*
X2989750Y1426951D01*
X2988439Y1426077D01*
X2986911Y1425785D01*
X2985165Y1426368D01*
X2983855Y1427826D01*
X2982981Y1429576D01*
X2982763Y1431618D01*
X2982981Y1433660D01*
X2983855Y1435410D01*
X2985165Y1436868D01*
X2986911Y1437451D01*
X2988439Y1437160D01*
X2989531Y1436576D01*
X2990623Y1435410D01*
G01X2736890Y1459852D02*
X2746496Y1472685D01*
G01X2741693Y1475018D02*
Y1457518D01*
G01X2746496Y1459852D02*
X2736890Y1472685D01*
G01X2735143Y1466268D02*
X2748243D01*
G01X2773855D02*
X2779531D01*
G01X2806890Y1460435D02*
Y1477935D01*
X2811256D01*
X2813003Y1477060D01*
X2814313Y1475893D01*
X2815405Y1474144D01*
X2816278Y1472101D01*
X2816496Y1469185D01*
X2816278Y1466268D01*
X2815405Y1464226D01*
X2814313Y1462476D01*
X2813003Y1461310D01*
X2811256Y1460435D01*
X2806890D01*
G01X2825918Y1468310D02*
X2832905D01*
X2832250Y1470352D01*
X2831158Y1471518D01*
X2829630Y1472101D01*
X2828101Y1471810D01*
X2826791Y1470935D01*
X2825918Y1468893D01*
X2825481Y1467143D01*
Y1465393D01*
X2825918Y1463643D01*
X2827010Y1461893D01*
X2828320Y1460727D01*
X2829848Y1460435D01*
X2831376Y1461018D01*
X2832905Y1462768D01*
G01X2842981Y1460435D02*
Y1472101D01*
G01Y1469185D02*
X2843855Y1470643D01*
X2845165Y1471810D01*
X2846911Y1472101D01*
X2848439Y1471810D01*
X2849750Y1470643D01*
X2850405Y1468602D01*
Y1460435D01*
G01X2864193D02*
X2862883Y1460727D01*
X2861573Y1461893D01*
X2860699Y1463935D01*
X2860263Y1466268D01*
X2860699Y1468602D01*
X2861573Y1470643D01*
X2862883Y1471810D01*
X2864193Y1472101D01*
X2865503Y1471810D01*
X2866813Y1470643D01*
X2867686Y1468602D01*
X2867905Y1466268D01*
X2867686Y1463935D01*
X2866813Y1461893D01*
X2865503Y1460727D01*
X2864193Y1460435D01*
G01X2881693Y1477935D02*
Y1460435D01*
G01X2878636Y1472101D02*
X2884750D01*
G01X2895918Y1468310D02*
X2902905D01*
X2902250Y1470352D01*
X2901158Y1471518D01*
X2899630Y1472101D01*
X2898101Y1471810D01*
X2896791Y1470935D01*
X2895918Y1468893D01*
X2895481Y1467143D01*
Y1465393D01*
X2895918Y1463643D01*
X2897010Y1461893D01*
X2898320Y1460727D01*
X2899848Y1460435D01*
X2901376Y1461018D01*
X2902905Y1462768D01*
G01X2913418Y1462476D02*
X2914510Y1461310D01*
X2916038Y1460435D01*
X2917348D01*
X2918658Y1461018D01*
X2919531Y1461893D01*
X2919968Y1463059D01*
X2919750Y1464810D01*
X2918876Y1465685D01*
X2914946Y1467435D01*
X2914073Y1469477D01*
X2914510Y1470935D01*
X2915383Y1471810D01*
X2916693Y1472101D01*
X2918003Y1471810D01*
X2919313Y1470935D01*
G01X2951693Y1477935D02*
Y1460435D01*
G01X2948636Y1472101D02*
X2954750D01*
G01X2965481Y1460435D02*
Y1477935D01*
G01Y1469477D02*
X2966573Y1470935D01*
X2967665Y1471810D01*
X2969411Y1472101D01*
X2970721Y1471810D01*
X2972250Y1470643D01*
X2972905Y1468893D01*
Y1460435D01*
G01X2990623D02*
Y1472101D01*
G01Y1470060D02*
X2989750Y1471226D01*
X2988439Y1471810D01*
X2986911Y1472101D01*
X2985383Y1471518D01*
X2984073Y1470352D01*
X2983199Y1468602D01*
X2982763Y1466268D01*
X2983199Y1463935D01*
X2984073Y1462185D01*
X2985383Y1461018D01*
X2986911Y1460435D01*
X2988439Y1460727D01*
X2989750Y1461601D01*
X2990623Y1462768D01*
G01X3004193Y1477935D02*
Y1460435D01*
G01X3001136Y1472101D02*
X3007250D01*
G01X3039193Y1477935D02*
Y1460435D01*
G01X3036136Y1472101D02*
X3042250D01*
G01X3052981Y1460435D02*
Y1477935D01*
G01Y1469477D02*
X3054073Y1470935D01*
X3055165Y1471810D01*
X3056911Y1472101D01*
X3058221Y1471810D01*
X3059750Y1470643D01*
X3060405Y1468893D01*
Y1460435D01*
G01X3074193Y1472101D02*
Y1460435D01*
G01Y1476768D02*
X3073756Y1477060D01*
Y1477643D01*
X3074193Y1477935D01*
X3074630Y1477643D01*
Y1477060D01*
X3074193Y1476768D01*
G01X3088418Y1462476D02*
X3089510Y1461310D01*
X3091038Y1460435D01*
X3092348D01*
X3093658Y1461018D01*
X3094531Y1461893D01*
X3094968Y1463059D01*
X3094750Y1464810D01*
X3093876Y1465685D01*
X3089946Y1467435D01*
X3089073Y1469477D01*
X3089510Y1470935D01*
X3090383Y1471810D01*
X3091693Y1472101D01*
X3093003Y1471810D01*
X3094313Y1470935D01*
G01X3124073Y1477935D02*
X3129313D01*
G01X3126693D02*
Y1460435D01*
G01X3124073D02*
X3129313D01*
G01X3137643D02*
Y1472101D01*
G01Y1468893D02*
X3138298Y1470352D01*
X3139390Y1471518D01*
X3140918Y1472101D01*
X3142446Y1471518D01*
X3143538Y1470352D01*
X3144193Y1468893D01*
Y1460435D01*
G01Y1468893D02*
X3144848Y1470352D01*
X3145939Y1471518D01*
X3147468Y1472101D01*
X3148996Y1471518D01*
X3150088Y1470352D01*
X3150743Y1468602D01*
Y1460435D01*
G01X3157763Y1454602D02*
Y1472101D01*
G01Y1469477D02*
X3158855Y1470935D01*
X3159946Y1471810D01*
X3161693Y1472101D01*
X3163221Y1471810D01*
X3164750Y1470352D01*
X3165405Y1468310D01*
X3165623Y1466268D01*
X3165405Y1464226D01*
X3164750Y1462185D01*
X3163439Y1461018D01*
X3161693Y1460435D01*
X3160165Y1460727D01*
X3158636Y1461601D01*
X3157763Y1462768D01*
G01X3175918Y1468310D02*
X3182905D01*
X3182250Y1470352D01*
X3181158Y1471518D01*
X3179630Y1472101D01*
X3178101Y1471810D01*
X3176791Y1470935D01*
X3175918Y1468893D01*
X3175481Y1467143D01*
Y1465393D01*
X3175918Y1463643D01*
X3177010Y1461893D01*
X3178320Y1460727D01*
X3179848Y1460435D01*
X3181376Y1461018D01*
X3182905Y1462768D01*
G01X3200623Y1477935D02*
Y1460435D01*
G01Y1463059D02*
X3199750Y1461601D01*
X3198439Y1460727D01*
X3196911Y1460435D01*
X3195165Y1461018D01*
X3193855Y1462476D01*
X3192981Y1464226D01*
X3192763Y1466268D01*
X3192981Y1468310D01*
X3193855Y1470060D01*
X3195165Y1471518D01*
X3196911Y1472101D01*
X3198439Y1471810D01*
X3199531Y1471226D01*
X3200623Y1470060D01*
G01X3218123Y1460435D02*
Y1472101D01*
G01Y1470060D02*
X3217250Y1471226D01*
X3215939Y1471810D01*
X3214411Y1472101D01*
X3212883Y1471518D01*
X3211573Y1470352D01*
X3210699Y1468602D01*
X3210263Y1466268D01*
X3210699Y1463935D01*
X3211573Y1462185D01*
X3212883Y1461018D01*
X3214411Y1460435D01*
X3215939Y1460727D01*
X3217250Y1461601D01*
X3218123Y1462768D01*
G01X3227981Y1460435D02*
Y1472101D01*
G01Y1469185D02*
X3228855Y1470643D01*
X3230165Y1471810D01*
X3231911Y1472101D01*
X3233439Y1471810D01*
X3234750Y1470643D01*
X3235405Y1468602D01*
Y1460435D01*
G01X3252686Y1470643D02*
X3251158Y1471810D01*
X3249848Y1472101D01*
X3248101Y1471518D01*
X3246791Y1470352D01*
X3245918Y1468310D01*
X3245699Y1466268D01*
X3245918Y1464226D01*
X3246791Y1462476D01*
X3248101Y1461018D01*
X3249848Y1460435D01*
X3251376Y1461018D01*
X3252686Y1462185D01*
G01X3263418Y1468310D02*
X3270405D01*
X3269750Y1470352D01*
X3268658Y1471518D01*
X3267130Y1472101D01*
X3265601Y1471810D01*
X3264291Y1470935D01*
X3263418Y1468893D01*
X3262981Y1467143D01*
Y1465393D01*
X3263418Y1463643D01*
X3264510Y1461893D01*
X3265820Y1460727D01*
X3267348Y1460435D01*
X3268876Y1461018D01*
X3270405Y1462768D01*
G01X0Y3937D02*
G03X3937Y0I3937J0D01*
G01X0Y3937D02*
G03X3937Y0I3937J0D01*
G01D02*
X779528D01*
G01X3937D02*
X779528D01*
G01X0Y1456693D02*
Y3937D01*
G01Y1456693D02*
Y3937D01*
G01X7874Y1460630D02*
X3937D01*
G01D02*
X7874D01*
G01X3937D02*
G03X0Y1456693I0J-3937D01*
G01X3937Y1460630D02*
G03X0Y1456693I0J-3937D01*
G01X101378Y1519685D02*
G03X97441Y1515748I0J-3937D01*
G01X101378Y1519685D02*
G03X97441Y1515748I0J-3937D01*
G01D02*
Y1509055D01*
G01Y1515748D02*
Y1509055D01*
G01X93504Y1505118D02*
X67913D01*
G01X93504D02*
G03X97441Y1509055I0J3937D01*
G01X93504Y1505118D02*
G03X97441Y1509055I0J3937D01*
G01X67913Y1505118D02*
X93504D01*
G01X63976Y1515748D02*
G03X60039Y1519685I-3937J0D01*
G01X63976Y1515748D02*
G03X60039Y1519685I-3937J0D01*
G01X63976Y1509055D02*
Y1515748D01*
G01Y1509055D02*
G03X67913Y1505118I3937J0D01*
G01X63976Y1509055D02*
G03X67913Y1505118I3937J0D01*
G01X63976Y1515748D02*
Y1509055D01*
G01X7874Y1460630D02*
G03X11811Y1464567I0J3937D01*
G01X7874Y1460630D02*
G03X11811Y1464567I0J3937D01*
G01X15748Y1519685D02*
G03X11811Y1515748I0J-3937D01*
G01X15748Y1519685D02*
G03X11811Y1515748I0J-3937D01*
G01D02*
Y1464567D01*
G01Y1515748D02*
Y1464567D01*
G01X60039Y1519685D02*
X15748D01*
G01X60039D02*
X15748D01*
G01X141181Y277843D02*
G03X148106Y264712I37662J11471D01*
G01X141181Y277843D02*
G03X148106Y264712I37662J11471D01*
G01X141181Y277843D02*
G03X121220I-9980J-3040D01*
G01X114295Y264712D02*
G03X121220Y277843I-30737J24602D01*
G01X141181D02*
G03X121220I-9980J-3040D01*
G01X114295Y264712D02*
G03X121220Y277843I-30737J24601D01*
G01X114295Y264712D02*
G03X148106I16905J-13531D01*
G01X114295D02*
G03X148106I16905J-13531D01*
G01X141181Y730599D02*
G03X148106Y717468I37662J11471D01*
G01X141181Y730599D02*
G03X148106Y717468I37662J11471D01*
G01X141181Y730599D02*
G03X121220I-9980J-3040D01*
G01X114295Y717468D02*
G03X121220Y730599I-30737J24601D01*
G01X141181D02*
G03X121220I-9980J-3040D01*
G01X114295Y717468D02*
G03X121220Y730599I-30737J24601D01*
G01X114295Y717468D02*
G03X148106I16905J-13531D01*
G01X114295D02*
G03X148106I16905J-13531D01*
G01X114295Y1170224D02*
G03X148106I16905J-13531D01*
G01X114295D02*
G03X148106I16905J-13531D01*
G01X141181Y1183355D02*
G03X148106Y1170224I37662J11471D01*
G01X141181Y1183355D02*
G03X148106Y1170224I37662J11471D01*
G01X141181Y1183355D02*
G03X121220I-9980J-3040D01*
G01X141181D02*
G03X121220I-9980J-3040D01*
G01X114295Y1170224D02*
G03X121220Y1183355I-30737J24602D01*
G01X114295Y1170224D02*
G03X121220Y1183355I-30737J24601D01*
G01X280709Y1519685D02*
X101378D01*
G01X280709D02*
X101378D01*
G01X284646Y1515748D02*
G03X280709Y1519685I-3937J0D01*
G01X284646Y1515748D02*
G03X280709Y1519685I-3937J0D01*
G01X284646Y1500000D02*
Y1515748D01*
G01Y1500000D02*
G03X288583Y1496063I3937J0D01*
G01X493307D02*
X288583D01*
G01X284646Y1500000D02*
G03X288583Y1496063I3937J0D01*
G01X493307D02*
X288583D01*
G01X284646Y1515748D02*
Y1500000D01*
G01X389213Y277843D02*
G03X369252I-9981J-3040D01*
G01X389213D02*
G03X369252I-9981J-3040D01*
G01X362327Y264712D02*
G03X369252Y277843I-30737J24602D01*
G01X362327Y264712D02*
G03X369252Y277843I-30737J24602D01*
G01X362327Y264712D02*
G03X396138I16905J-13531D01*
G01X362327D02*
G03X396138I16905J-13531D01*
G01X389213Y730599D02*
G03X369252I-9981J-3040D01*
G01X389213D02*
G03X369252I-9981J-3040D01*
G01X362327Y717468D02*
G03X369252Y730599I-30737J24602D01*
G01X362327Y717468D02*
G03X369252Y730599I-30737J24602D01*
G01X362327Y717468D02*
G03X396138I16905J-13531D01*
G01X362327D02*
G03X396138I16905J-13531D01*
G01X362327Y1170224D02*
G03X396138I16905J-13531D01*
G01X362327D02*
G03X396138I16905J-13531D01*
G01X389213Y1183355D02*
G03X369252I-9981J-3040D01*
G01X389213D02*
G03X369252I-9981J-3040D01*
G01X362327Y1170224D02*
G03X369252Y1183355I-30737J24602D01*
G01X362327Y1170224D02*
G03X369252Y1183355I-30737J24602D01*
G01X322441Y1503937D02*
G03Y1496063I0J-3937D01*
G01X459449Y1503937D02*
X322441D01*
G01X459449D02*
X322441D01*
G01D02*
G03Y1496063I0J-3937D01*
G01X296457Y1519685D02*
G03X292520Y1515748I0J-3937D01*
G01X296457Y1519685D02*
X485433D01*
G01X296457D02*
G03X292520Y1515748I0J-3937D01*
G01X296457Y1519685D02*
X485433D01*
G01X304331Y1503937D02*
X292520D01*
G01Y1515748D02*
Y1503937D01*
G01X304331D02*
X292520D01*
G01Y1515748D02*
Y1503937D01*
G01X304331Y1496063D02*
G03Y1503937I0J3937D01*
G01Y1496063D02*
G03Y1503937I0J3937D01*
G01X389213Y277843D02*
G03X396138Y264712I37662J11471D01*
G01X389213Y277843D02*
G03X396138Y264712I37662J11470D01*
G01X389213Y730599D02*
G03X396138Y717468I37662J11471D01*
G01X389213Y730599D02*
G03X396138Y717468I37662J11470D01*
G01X389213Y1183355D02*
G03X396138Y1170224I37662J11471D01*
G01X389213Y1183355D02*
G03X396138Y1170224I37662J11470D01*
G01X477559Y1503937D02*
G03Y1496063I0J-3937D01*
G01X459449D02*
G03Y1503937I0J3937D01*
G01X489370D02*
X477559D01*
G01D02*
G03Y1496063I0J-3937D01*
G01X459449D02*
G03Y1503937I0J3937D01*
G01X489370D02*
X477559D01*
G01X489370Y1515748D02*
G03X485433Y1519685I-3937J0D01*
G01X489370Y1515748D02*
G03X485433Y1519685I-3937J0D01*
G01X501181D02*
G03X497244Y1515748I0J-3937D01*
G01X680512Y1519685D02*
X501181D01*
G01D02*
G03X497244Y1515748I0J-3937D01*
G01X680512Y1519685D02*
X501181D01*
G01X489370Y1515748D02*
Y1503937D01*
G01X493307Y1496063D02*
G03X497244Y1500000I0J3937D01*
G01Y1515748D02*
Y1500000D01*
G01X489370Y1515748D02*
Y1503937D01*
G01X493307Y1496063D02*
G03X497244Y1500000I0J3937D01*
G01Y1515748D02*
Y1500000D01*
G01X637244Y277843D02*
G03X644169Y264712I37662J11471D01*
G01X637244Y277843D02*
G03X644169Y264712I37662J11471D01*
G01X637244Y277843D02*
G03X617283I-9980J-3040D01*
G01X610358Y264712D02*
G03X617283Y277843I-30737J24602D01*
G01X637244D02*
G03X617283I-9980J-3040D01*
G01X610358Y264712D02*
G03X617283Y277843I-30737J24601D01*
G01X610358Y264712D02*
G03X644169I16906J-13531D01*
G01X610358D02*
G03X644169I16906J-13531D01*
G01X637244Y730599D02*
G03X644169Y717468I37662J11471D01*
G01X637244Y730599D02*
G03X644169Y717468I37662J11471D01*
G01X637244Y730599D02*
G03X617283I-9980J-3040D01*
G01X610358Y717468D02*
G03X617283Y730599I-30737J24601D01*
G01X637244D02*
G03X617283I-9980J-3040D01*
G01X610358Y717468D02*
G03X617283Y730599I-30737J24601D01*
G01X610358Y717468D02*
G03X644169I16906J-13531D01*
G01X610358D02*
G03X644169I16906J-13531D01*
G01X610358Y1170224D02*
G03X644169I16906J-13531D01*
G01X610358D02*
G03X644169I16906J-13531D01*
G01X637244Y1183355D02*
G03X644169Y1170224I37662J11471D01*
G01X637244Y1183355D02*
G03X644169Y1170224I37662J11471D01*
G01X637244Y1183355D02*
G03X617283I-9980J-3040D01*
G01X637244D02*
G03X617283I-9980J-3040D01*
G01X610358Y1170224D02*
G03X617283Y1183355I-30737J24602D01*
G01X610358Y1170224D02*
G03X617283Y1183355I-30737J24601D01*
G01X730339Y383610D02*
G03X764149I16905J-13531D01*
G01X730339Y383609D02*
G03X764150I16905J-13530D01*
G01X757225Y396741D02*
G03X764149Y383610I37663J11469D01*
G01X757224Y396741D02*
G03X764150Y383609I37662J11471D01*
G01X757225Y396741D02*
G03X737264I-9981J-3040D01*
G01X730339Y383610D02*
G03X737264Y396741I-30737J24602D01*
G01X757224D02*
G03X737264I-9980J-3041D01*
G01X730339Y383609D02*
G03X737264Y396741I-30738J24601D01*
G01X757225Y829811D02*
G03X764149Y816680I37663J11469D01*
G01X757224Y829811D02*
G03X764150Y816680I37662J11473D01*
G01X757225Y829811D02*
G03X737264I-9981J-3039D01*
G01X757224D02*
G03X737264I-9980J-3040D01*
G01X730339Y816680D02*
G03X737264Y829811I-30737J24602D01*
G01X730339Y816680D02*
G03X737264Y829811I-30737J24602D01*
G01X730339Y816680D02*
G03X764149I16905J-13531D01*
G01X730339D02*
G03X764150I16905J-13531D01*
G01X721850Y1519685D02*
G03X717913Y1515748I0J-3937D01*
G01X775591Y1519685D02*
X721850D01*
G01D02*
G03X717913Y1515748I0J-3937D01*
G01X775591Y1519685D02*
X721850D01*
G01X713976Y1505118D02*
G03X717913Y1509055I0J3937D01*
G01Y1515748D02*
Y1509055D01*
G01X713976Y1505118D02*
G03X717913Y1509055I0J3937D01*
G01Y1515748D02*
Y1509055D01*
G01X684449Y1515748D02*
G03X680512Y1519685I-3937J0D01*
G01X684449Y1515748D02*
G03X680512Y1519685I-3937J0D01*
G01X684449Y1509055D02*
Y1515748D01*
G01Y1509055D02*
G03X688386Y1505118I3937J0D01*
G01X713976D02*
X688386D01*
G01X684449Y1509055D02*
G03X688386Y1505118I3937J0D01*
G01D02*
X713976D01*
G01X684449Y1515748D02*
Y1509055D01*
G01X791339Y3937D02*
G03X795276Y0I3937J0D01*
G01D02*
X892317D01*
G01X791339Y3937D02*
Y23622D01*
G01Y3937D02*
G03X795276Y0I3937J0D01*
G01X791339Y3937D02*
Y23622D01*
G01X795276Y0D02*
X892317D01*
G01X783465Y54331D02*
G03X791339I3937J0D01*
G01X783465D02*
G03X791339I3937J0D01*
G01Y23622D02*
G03X783465I-3937J0D01*
G01X791339D02*
G03X783465I-3937J0D01*
G01X779528Y0D02*
G03X783465Y3937I0J3937D01*
G01X779528Y0D02*
G03X783465Y3937I0J3937D01*
G01X791339Y54331D02*
Y181890D01*
G01Y54331D02*
Y181890D01*
G01X783465Y3937D02*
Y185827D01*
G01Y3937D02*
Y185827D01*
G01X811024Y181890D02*
G03X822835Y193701I0J11811D01*
G01X791339Y181890D02*
X811024D01*
G01D02*
G03X822835Y193701I0J11811D01*
G01X791339Y181890D02*
X811024D01*
G01X787402Y189764D02*
G03X783465Y185827I0J-3937D01*
G01X787402Y189764D02*
G03X783465Y185827I0J-3937D01*
G01X811024Y189764D02*
G03X814961Y193701I0J3937D01*
G01X787402Y189764D02*
X811024D01*
G01D02*
G03X814961Y193701I0J3937D01*
G01X787402Y189764D02*
X811024D01*
G01X822835Y193701D02*
Y240157D01*
G01Y193701D02*
Y240157D01*
G01X814961Y193701D02*
Y244094D01*
G01Y193701D02*
Y244094D01*
G01X818898Y248031D02*
G03X814961Y244094I0J-3937D01*
G01X818898Y248031D02*
G03X814961Y244094I0J-3937D01*
G01X928098Y240157D02*
X822835D01*
G01X928098D02*
X822835D01*
G01X818898Y248031D02*
X1055118D01*
G01D02*
X818898D01*
G01X954331Y1503937D02*
X817323D01*
G01X954331D02*
X817323D01*
G01X791339Y1519685D02*
G03X787402Y1515748I0J-3937D01*
G01X791339Y1519685D02*
X980315D01*
G01X791339D02*
G03X787402Y1515748I0J-3937D01*
G01X791339Y1519685D02*
X980315D01*
G01X817323Y1503937D02*
G03Y1496063I0J-3937D01*
G01X799213D02*
G03Y1503937I0J3937D01*
G01D02*
X787402D01*
G01Y1515748D02*
Y1503937D01*
G01X799213D02*
X787402D01*
G01X817323D02*
G03Y1496063I0J-3937D01*
G01X799213D02*
G03Y1503937I0J3937D01*
G01X787402Y1515748D02*
Y1503937D01*
G01X779528Y1515748D02*
G03X775591Y1519685I-3937J0D01*
G01X779528Y1515748D02*
G03X775591Y1519685I-3937J0D01*
G01X779528Y1500000D02*
Y1515748D01*
G01Y1500000D02*
G03X783465Y1496063I3937J0D01*
G01X988189D02*
X783465D01*
G01X779528Y1500000D02*
G03X783465Y1496063I3937J0D01*
G01X988189D02*
X783465D01*
G01X779528Y1515748D02*
Y1500000D01*
G01X900191Y0D02*
G03X892317I-3937J0D01*
G01X896254D02*
Y-394D01*
G01Y0D02*
Y394D01*
G01X895762Y0D02*
X896746D01*
G01X900191D02*
G03X892317I-3937J0D01*
G01X900191D02*
X1212598D01*
G01X900191D02*
X1212598D01*
G01X953294Y248031D02*
G03Y240157I1J-3937D01*
G01X1051181D02*
X953294D01*
G01Y248031D02*
G03Y240157I1J-3937D01*
G01X928098D02*
G03Y248031I0J3937D01*
G01Y240157D02*
G03Y248031I0J3937D01*
G01X1051181Y240157D02*
X953294D01*
G01X971398Y718788D02*
G03X951437I-9980J-3040D01*
G01X944512Y705657D02*
G03X951437Y718788I-30737J24602D01*
G01X971398D02*
G03X951437I-9980J-3040D01*
G01X944512Y705657D02*
G03X951437Y718788I-30737J24602D01*
G01X944512Y705657D02*
G03X978323I16905J-13531D01*
G01X944512D02*
G03X978323I16905J-13531D01*
G01X944512Y974161D02*
G03X978323I16905J-13531D01*
G01X944512D02*
G03X978323I16905J-13531D01*
G01X971398Y987292D02*
G03X951437I-9980J-3040D01*
G01X944512Y974161D02*
G03X951437Y987292I-30737J24602D01*
G01X971398D02*
G03X951437I-9980J-3040D01*
G01X944512Y974161D02*
G03X951437Y987292I-30737J24602D01*
G01X954331Y1496063D02*
G03Y1503937I0J3937D01*
G01Y1496063D02*
G03Y1503937I0J3937D01*
G01X1051181Y193701D02*
G03X1062992Y181890I11811J0D01*
G01X1051181Y193701D02*
G03X1062992Y181890I11811J0D01*
G01X1051181Y240157D02*
Y193701D01*
G01Y240157D02*
Y193701D01*
G01X971398Y718788D02*
G03X978323Y705657I37662J11471D01*
G01X971398Y718788D02*
G03X978323Y705657I37662J11470D01*
G01X971398Y987292D02*
G03X978323Y974161I37662J11471D01*
G01X971398Y987292D02*
G03X978323Y974161I37662J11470D01*
G01X1059196Y1519685D02*
X996063D01*
G01X1059196D02*
X996063D01*
G01X984252Y1515748D02*
G03X980315Y1519685I-3937J0D01*
G01X984252Y1515748D02*
G03X980315Y1519685I-3937J0D01*
G01X996063D02*
G03X992126Y1515748I0J-3937D01*
G01X996063Y1519685D02*
G03X992126Y1515748I0J-3937D01*
G01X972441Y1503937D02*
G03Y1496063I0J-3937D01*
G01X984252Y1503937D02*
X972441D01*
G01X984252Y1515748D02*
Y1503937D01*
G01X972441D02*
G03Y1496063I0J-3937D01*
G01X988189D02*
G03X992126Y1500000I0J3937D01*
G01Y1515748D02*
Y1500000D01*
G01X984252Y1515748D02*
Y1503937D01*
G01D02*
X972441D01*
G01X988189Y1496063D02*
G03X992126Y1500000I0J3937D01*
G01Y1515748D02*
Y1500000D01*
G01X1133071Y189764D02*
G03Y181890I0J-3937D01*
G01D02*
X1216535D01*
G01X1133071D02*
X1216535D01*
G01X1133071Y189764D02*
G03Y181890I0J-3937D01*
G01X1102362D02*
G03Y189764I0J3937D01*
G01Y181890D02*
G03Y189764I0J3937D01*
G01X1062992Y181890D02*
X1102362D01*
G01X1062992D02*
X1102362D01*
G01X1059055Y244094D02*
G03X1055118Y248031I-3937J0D01*
G01X1059055Y244094D02*
G03X1055118Y248031I-3937J0D01*
G01X1059055Y244094D02*
Y193701D01*
G01Y244094D02*
Y193701D01*
G01X1062992Y189764D02*
X1220472D01*
G01X1059055Y193701D02*
G03X1062992Y189764I3937J0D01*
G01X1059055Y193701D02*
G03X1062992Y189764I3937J0D01*
G01D02*
X1220472D01*
G01X1085630Y1417323D02*
G03X1089567Y1421260I0J3937D01*
G01X1085630Y1417323D02*
G03X1089567Y1421260I0J3937D01*
G01X1072638D02*
G03X1076575Y1417322I3937J-1D01*
G01X1085630Y1417323D02*
X1076575D01*
G01X1072638Y1421260D02*
G03X1076575Y1417323I3937J0D01*
G01D02*
X1085630D01*
G01X1089567Y1506243D02*
Y1421260D01*
G01Y1506243D02*
Y1421260D01*
G01X1072638D02*
Y1506243D01*
G01D02*
Y1421260D01*
G01X1103009Y1519685D02*
G03X1100225Y1518532I0J-3937D01*
G01X1207283Y1519685D02*
X1103009D01*
G01D02*
G03X1100225Y1518532I0J-3937D01*
G01X1207283Y1519685D02*
X1103009D01*
G01X1090720Y1509027D02*
G03X1089567Y1506243I2784J-2784D01*
G01X1100225Y1518532D02*
X1090720Y1509027D01*
G01D02*
G03X1089567Y1506243I2784J-2784D01*
G01X1100225Y1518532D02*
X1090720Y1509027D01*
G01X1061980Y1518532D02*
G03X1059196Y1519685I-2784J-2784D01*
G01X1061980Y1518532D02*
G03X1059196Y1519685I-2784J-2784D01*
G01X1071485Y1509027D02*
X1061980Y1518532D01*
G01X1072638Y1506243D02*
G03X1071485Y1509027I-3937J0D01*
G01X1072638Y1506243D02*
G03X1071485Y1509027I-3937J0D01*
G01X1061980Y1518532D02*
X1071485Y1509027D01*
G01X1216535Y54331D02*
G03X1224409I3937J0D01*
G01X1216535D02*
Y181890D01*
G01Y54331D02*
Y181890D01*
G01Y54331D02*
G03X1224409I3937J0D01*
G01Y23622D02*
G03X1216535I-3937J0D01*
G01X1224409D02*
G03X1216535I-3937J0D01*
G01X1212598Y0D02*
G03X1216535Y3937I0J3937D01*
G01D02*
Y23622D01*
G01X1212598Y0D02*
G03X1216535Y3937I0J3937D01*
G01X1224409D02*
G03X1228346Y0I3937J0D01*
G01X1224409Y185827D02*
Y3937D01*
G01X1216535D02*
Y23622D01*
G01X1224409Y3937D02*
G03X1228346Y0I3937J0D01*
G01X1224409Y3937D02*
Y185827D01*
G01X1228346Y0D02*
X1930906D01*
G01X1228346D02*
X1930906D01*
G01X1224409Y185827D02*
G03X1220472Y189764I-3937J0D01*
G01X1224409Y185827D02*
G03X1220472Y189764I-3937J0D01*
G01X1164984Y383609D02*
G03X1198795I16906J-13530D01*
G01X1164984D02*
G03X1198795I16906J-13530D01*
G01X1191870Y396741D02*
G03X1198795Y383610I37662J11471D01*
G01X1191870Y396741D02*
G03X1198795Y383609I37663J11469D01*
G01X1191870Y396741D02*
G03X1171909I-9980J-3040D01*
G01X1164984Y383610D02*
G03X1171909Y396741I-30737J24602D01*
G01X1191870D02*
G03X1171909I-9980J-3040D01*
G01X1164984Y383609D02*
G03X1171909Y396741I-30737J24601D01*
G01X1164984Y974161D02*
G03X1198795I16906J-13531D01*
G01X1164984D02*
G03X1198795I16906J-13531D01*
G01X1191870Y987292D02*
G03X1198795Y974161I37662J11471D01*
G01X1191870Y987292D02*
G03X1198795Y974161I37662J11471D01*
G01X1191870Y987292D02*
G03X1171909I-9980J-3040D01*
G01X1164984Y974161D02*
G03X1171909Y987292I-30737J24602D01*
G01X1191870D02*
G03X1171909I-9980J-3040D01*
G01X1164984Y974161D02*
G03X1171909Y987292I-30737J24601D01*
G01X1240748Y1505118D02*
G03X1244685Y1509055I0J3937D01*
G01X1240748Y1505118D02*
G03X1244685Y1509055I0J3937D01*
G01X1211220Y1515748D02*
G03X1207283Y1519685I-3937J0D01*
G01X1211220Y1515748D02*
G03X1207283Y1519685I-3937J0D01*
G01X1211220Y1509055D02*
Y1515748D01*
G01Y1509055D02*
G03X1215157Y1505118I3937J0D01*
G01X1240748D02*
X1215157D01*
G01X1211220Y1509055D02*
G03X1215157Y1505118I3937J0D01*
G01D02*
X1240748D01*
G01X1211220Y1515748D02*
Y1509055D01*
G01X1311851Y277843D02*
G03X1318775Y264712I37663J11469D01*
G01X1311850Y277843D02*
G03X1318776Y264712I37661J11473D01*
G01X1311851Y277843D02*
G03X1291890I-9980J-3040D01*
G01X1284965Y264712D02*
G03X1291890Y277843I-30737J24602D01*
G01X1311850D02*
G03X1291890I-9980J-3040D01*
G01X1284965Y264712D02*
G03X1291890Y277843I-30737J24602D01*
G01X1284965Y264712D02*
G03X1318775I16905J-13531D01*
G01X1284965D02*
G03X1318776I16906J-13531D01*
G01X1311851Y730599D02*
G03X1318775Y717468I37663J11469D01*
G01X1311850Y730599D02*
G03X1318776Y717468I37661J11473D01*
G01X1311851Y730599D02*
G03X1291890I-9980J-3040D01*
G01X1284965Y717468D02*
G03X1291891Y730599I-30736J24604D01*
G01X1311850D02*
G03X1291890I-9980J-3040D01*
G01X1284965Y717468D02*
G03X1291890Y730599I-30737J24602D01*
G01X1284965Y717468D02*
G03X1318775I16905J-13531D01*
G01X1284965D02*
G03X1318776I16906J-13531D01*
G01X1284965Y1170224D02*
G03X1318775I16905J-13531D01*
G01X1284965D02*
G03X1318776I16906J-13531D01*
G01X1311851Y1183355D02*
G03X1318775Y1170224I37663J11469D01*
G01X1311850Y1183355D02*
G03X1318776Y1170224I37661J11473D01*
G01X1311851Y1183355D02*
G03X1291890I-9980J-3040D01*
G01X1311850D02*
G03X1291890I-9980J-3040D01*
G01X1284965Y1170224D02*
G03X1291890Y1183355I-30737J24602D01*
G01X1284965Y1170224D02*
G03X1291890Y1183355I-30737J24602D01*
G01X1248622Y1519685D02*
G03X1244685Y1515748I0J-3937D01*
G01X1427953Y1519685D02*
X1248622D01*
G01D02*
G03X1244685Y1515748I0J-3937D01*
G01X1427953Y1519685D02*
X1248622D01*
G01X1244685Y1515748D02*
Y1509055D01*
G01Y1515748D02*
Y1509055D01*
G01X1431890Y1515748D02*
G03X1427953Y1519685I-3937J0D01*
G01X1431890Y1515748D02*
G03X1427953Y1519685I-3937J0D01*
G01X1431890Y1500000D02*
Y1515748D01*
G01Y1500000D02*
G03X1435827Y1496063I3937J0D01*
G01X1431890Y1500000D02*
G03X1435827Y1496063I3937J0D01*
G01X1431890Y1515748D02*
Y1500000D01*
G01X1532996Y264712D02*
G03X1566807I16906J-13531D01*
G01X1532996D02*
G03X1566807I16906J-13531D01*
G01X1532996Y717468D02*
G03X1566807I16906J-13531D01*
G01X1532996D02*
G03X1566807I16906J-13531D01*
G01X1532996Y1170224D02*
G03X1566807I16906J-13531D01*
G01X1532996D02*
G03X1566807I16906J-13531D01*
G01X1469685Y1503937D02*
G03Y1496063I0J-3937D01*
G01X1451575D02*
G03Y1503937I0J3937D01*
G01X1606693D02*
X1469685D01*
G01X1606693D02*
X1469685D01*
G01D02*
G03Y1496063I0J-3937D01*
G01X1451575D02*
G03Y1503937I0J3937D01*
G01X1443701Y1519685D02*
G03X1439764Y1515748I0J-3937D01*
G01X1443701Y1519685D02*
X1632677D01*
G01X1443701D02*
G03X1439764Y1515748I0J-3937D01*
G01X1443701Y1519685D02*
X1632677D01*
G01X1451575Y1503937D02*
X1439764D01*
G01Y1515748D02*
Y1503937D01*
G01X1451575D02*
X1439764D01*
G01X1640551Y1496063D02*
X1435827D01*
G01X1439764Y1515748D02*
Y1503937D01*
G01X1640551Y1496063D02*
X1435827D01*
G01X1559882Y277843D02*
G03X1566807Y264712I37662J11471D01*
G01X1559882Y277843D02*
G03X1539921I-9980J-3040D01*
G01X1559882D02*
G03X1566807Y264712I37662J11471D01*
G01X1559882Y277843D02*
G03X1539921I-9980J-3040D01*
G01X1532996Y264712D02*
G03X1539921Y277843I-30737J24602D01*
G01X1532996Y264712D02*
G03X1539921Y277843I-30737J24602D01*
G01X1559882Y730599D02*
G03X1566807Y717468I37662J11471D01*
G01X1559882Y730599D02*
G03X1539921I-9980J-3040D01*
G01X1559882D02*
G03X1566807Y717468I37662J11471D01*
G01X1559882Y730599D02*
G03X1539921I-9980J-3040D01*
G01X1532996Y717468D02*
G03X1539921Y730599I-30737J24601D01*
G01X1532996Y717468D02*
G03X1539921Y730599I-30737J24601D01*
G01X1559882Y1183355D02*
G03X1539921I-9980J-3040D01*
G01X1559882D02*
G03X1539921I-9980J-3040D01*
G01X1559882D02*
G03X1566807Y1170224I37662J11471D01*
G01X1559882Y1183355D02*
G03X1566807Y1170224I37662J11471D01*
G01X1532996D02*
G03X1539921Y1183355I-30737J24602D01*
G01X1532996Y1170224D02*
G03X1539921Y1183355I-30737J24601D01*
G01X1636614Y1503937D02*
X1624803D01*
G01X1636614D02*
X1624803D01*
G01D02*
G03Y1496063I0J-3937D01*
G01X1606693D02*
G03Y1503937I0J3937D01*
G01X1624803D02*
G03Y1496063I0J-3937D01*
G01X1606693D02*
G03Y1503937I0J3937D01*
G01X1636614Y1515748D02*
G03X1632677Y1519685I-3937J0D01*
G01X1636614Y1515748D02*
G03X1632677Y1519685I-3937J0D01*
G01X1648425D02*
G03X1644488Y1515748I0J-3937D01*
G01X1827756Y1519685D02*
X1648425D01*
G01D02*
G03X1644488Y1515748I0J-3937D01*
G01X1827756Y1519685D02*
X1648425D01*
G01X1636614Y1515748D02*
Y1503937D01*
G01X1640551Y1496063D02*
G03X1644488Y1500000I0J3937D01*
G01Y1515748D02*
Y1500000D01*
G01X1636614Y1515748D02*
Y1503937D01*
G01X1640551Y1496063D02*
G03X1644488Y1500000I0J3937D01*
G01Y1515748D02*
Y1500000D01*
G01X1807914Y277843D02*
G03X1814838Y264712I37663J11469D01*
G01X1807913Y277843D02*
G03X1814839Y264712I37661J11473D01*
G01X1807914Y277843D02*
G03X1787953I-9980J-3040D01*
G01X1781028Y264712D02*
G03X1787953Y277843I-30737J24602D01*
G01X1807913D02*
G03X1787953I-9980J-3040D01*
G01X1781028Y264712D02*
G03X1787953Y277843I-30737J24602D01*
G01X1781028Y264712D02*
G03X1814839I16906J-13531D01*
G01X1781028D02*
G03X1814839I16906J-13531D01*
G01X1807914Y730599D02*
G03X1814838Y717468I37663J11469D01*
G01X1807913Y730599D02*
G03X1814839Y717468I37661J11473D01*
G01X1807914Y730599D02*
G03X1787953I-9980J-3040D01*
G01X1781028Y717468D02*
G03X1787954Y730599I-30736J24604D01*
G01X1807913D02*
G03X1787953I-9980J-3040D01*
G01X1781028Y717468D02*
G03X1787953Y730599I-30737J24602D01*
G01X1781028Y717468D02*
G03X1814838I16905J-13531D01*
G01X1781028D02*
G03X1814839I16906J-13531D01*
G01X1781028Y1170224D02*
G03X1814838I16905J-13531D01*
G01X1781028D02*
G03X1814839I16906J-13531D01*
G01X1807914Y1183355D02*
G03X1814838Y1170224I37662J11468D01*
G01X1807913Y1183355D02*
G03X1814839Y1170224I37661J11473D01*
G01X1807914Y1183355D02*
G03X1787953I-9980J-3040D01*
G01X1807913D02*
G03X1787953I-9980J-3040D01*
G01X1781028Y1170224D02*
G03X1787953Y1183355I-30737J24602D01*
G01X1781028Y1170224D02*
G03X1787953Y1183355I-30737J24602D01*
G01X1869094Y1519685D02*
G03X1865157Y1515748I0J-3937D01*
G01X1919094Y1519685D02*
X1869094D01*
G01D02*
G03X1865157Y1515748I0J-3937D01*
G01X1919094Y1519685D02*
X1869094D01*
G01X1865157Y1515748D02*
Y1509055D01*
G01Y1515748D02*
Y1509055D01*
G01X1861220Y1505118D02*
X1835630D01*
G01X1861220D02*
G03X1865157Y1509055I0J3937D01*
G01X1861220Y1505118D02*
G03X1865157Y1509055I0J3937D01*
G01X1835630Y1505118D02*
X1861220D01*
G01X1831693Y1515748D02*
G03X1827756Y1519685I-3937J0D01*
G01X1831693Y1515748D02*
G03X1827756Y1519685I-3937J0D01*
G01X1831693Y1509055D02*
Y1515748D01*
G01Y1509055D02*
G03X1835630Y1505118I3937J0D01*
G01X1831693Y1509055D02*
G03X1835630Y1505118I3937J0D01*
G01X1831693Y1515748D02*
Y1509055D01*
G01X1930906Y0D02*
G03X1934843Y3937I0J3937D01*
G01X1930906Y0D02*
G03X1934843Y3937I0J3937D01*
G01D02*
Y1456693D01*
G01Y3937D02*
Y1456693D01*
G01X1930906Y1460630D02*
X1926969D01*
G01X1934843Y1456693D02*
G03X1930906Y1460630I-3937J0D01*
G01X1934843Y1456693D02*
G03X1930906Y1460630I-3937J0D01*
G01D02*
X1926969D01*
G01X1923031Y1515748D02*
G03X1919094Y1519685I-3937J0D01*
G01X1923031Y1515748D02*
G03X1919094Y1519685I-3937J0D01*
G01X1923031Y1464567D02*
Y1515748D01*
G01Y1464567D02*
G03X1926969Y1460630I3937J0D01*
G01X1923031Y1464567D02*
G03X1926969Y1460630I3937J0D01*
G01X1923031Y1515748D02*
Y1464567D01*
G54D13*
G01X856759Y307692D02*
X855859D01*
G01X856759Y308842D02*
X855859D01*
G01X859236Y310169D02*
G02X856759Y307692I-2477J0D01*
G01X858086Y310169D02*
G02X856759Y308842I-1327J0D01*
G01X859236Y322124D02*
Y310169D01*
G01X858086Y322225D02*
Y310169D01*
G01X864925Y348890D02*
X859236Y322124D01*
G01X860850Y335253D02*
X858084Y322236D01*
G01X861848Y339948D02*
X861443Y338040D01*
G01X862846Y344643D02*
X862441Y342735D01*
G01X856759Y308842D02*
X855859D01*
G01X856759Y307692D02*
X855859D01*
G01X858086Y310169D02*
G02X856759Y308842I-1327J0D01*
G01X859236Y310169D02*
G02X856759Y307692I-2477J0D01*
G01X858086Y322225D02*
Y310169D01*
G01X859236Y322124D02*
Y310169D01*
G01X860850Y335253D02*
X858084Y322236D01*
G01X864925Y348890D02*
X859236Y322124D01*
G01X861848Y339948D02*
X861443Y338040D01*
G01X864925Y348890D02*
X859236Y322124D01*
G01X862846Y344643D02*
X862441Y342735D01*
G01X864925Y348890D02*
X859236Y322124D01*
G01X864925Y348890D02*
X859236Y322124D01*
G01X849673Y302968D02*
X848773D01*
G01X849673Y304118D02*
X848773D01*
G01X852150Y305445D02*
G02X849673Y302968I-2477J0D01*
G01X851000Y305445D02*
G02X849673Y304118I-1327J0D01*
G01X852150Y328472D02*
Y305445D01*
G01X851000Y328593D02*
Y305445D01*
G01X856520Y349049D02*
X852150Y328472D01*
G01X852302Y334725D02*
X851000Y328593D01*
G01X853299Y339420D02*
X852894Y337513D01*
G01X854296Y344116D02*
X853891Y342208D01*
G01X855439Y349497D02*
X854888Y346903D01*
G01X908884Y429681D02*
X856520Y349050D01*
G01X908052Y430513D02*
X855439Y349497D01*
G01X849673Y304118D02*
X848773D01*
G01X849673Y302968D02*
X848773D01*
G01X851000Y305445D02*
G02X849673Y304118I-1327J0D01*
G01X852150Y305445D02*
G02X849673Y302968I-2477J0D01*
G01X851000Y328593D02*
Y305445D01*
G01X852150Y328472D02*
Y305445D01*
G01X852302Y334725D02*
X851000Y328593D01*
G01X856520Y349049D02*
X852150Y328472D01*
G01X853299Y339420D02*
X852894Y337513D01*
G01X856520Y349049D02*
X852150Y328472D01*
G01X854296Y344116D02*
X853891Y342208D01*
G01X856520Y349049D02*
X852150Y328472D01*
G01X855439Y349497D02*
X854888Y346903D01*
G01X856520Y349049D02*
X852150Y328472D01*
G01X908052Y430513D02*
X855439Y349497D01*
G01X908884Y429681D02*
X856520Y349050D01*
G01X842586Y307692D02*
X841686D01*
G01X842586Y308842D02*
X841686D01*
G01X845063Y310169D02*
G02X842586Y307692I-2477J0D01*
G01X843913Y310169D02*
G02X842586Y308842I-1327J0D01*
G01X845063Y327454D02*
Y310169D01*
G01X843913Y327575D02*
Y310169D01*
G01X850250Y351853D02*
X845063Y327454D01*
G01X844318Y329482D02*
X843913Y327575D01*
G01X845316Y334177D02*
X844911Y332270D01*
G01X846314Y338872D02*
X845909Y336965D01*
G01X849169Y352301D02*
X846907Y341660D01*
G01X904343Y435148D02*
X850250Y351853D01*
G01X903511Y435980D02*
X849169Y352301D01*
G01X842586Y308842D02*
X841686D01*
G01X842586Y307692D02*
X841686D01*
G01X843913Y310169D02*
G02X842586Y308842I-1327J0D01*
G01X845063Y310169D02*
G02X842586Y307692I-2477J0D01*
G01X843913Y327575D02*
Y310169D01*
G01X845063Y327454D02*
Y310169D01*
G01X844318Y329482D02*
X843913Y327575D01*
G01X850250Y351853D02*
X845063Y327454D01*
G01X845316Y334177D02*
X844911Y332270D01*
G01X850250Y351853D02*
X845063Y327454D01*
G01X846314Y338872D02*
X845909Y336965D01*
G01X850250Y351853D02*
X845063Y327454D01*
G01X849169Y352301D02*
X846907Y341660D01*
G01X850250Y351853D02*
X845063Y327454D01*
G01X903511Y435980D02*
X849169Y352301D01*
G01X904343Y435148D02*
X850250Y351853D01*
G01X835500Y302968D02*
X834600D01*
G01X835500Y304118D02*
X834600D01*
G01X837977Y305445D02*
G02X835500Y302968I-2477J0D01*
G01X836827Y305445D02*
G02X835500Y304118I-1327J0D01*
G01X837977Y336700D02*
Y305445D01*
G01X836827Y336846D02*
Y305445D01*
G01X841563Y350819D02*
X837977Y336700D01*
G01X840494Y351286D02*
X836827Y336846D01*
G01X900821Y441924D02*
X841563Y350819D01*
G01X847658Y362300D02*
X840494Y351286D01*
G01X850433Y366567D02*
X849212Y364689D01*
G01X853050Y370591D02*
X851987Y368956D01*
G01X886337Y421766D02*
X854604Y372980D01*
G01X835500Y304118D02*
X834600D01*
G01X835500Y302968D02*
X834600D01*
G01X836827Y305445D02*
G02X835500Y304118I-1327J0D01*
G01X837977Y305445D02*
G02X835500Y302968I-2477J0D01*
G01X836827Y336846D02*
Y305445D01*
G01X837977Y336700D02*
Y305445D01*
G01X840494Y351286D02*
X836827Y336846D01*
G01X841563Y350819D02*
X837977Y336700D01*
G01X847658Y362300D02*
X840494Y351286D01*
G01X900821Y441924D02*
X841563Y350819D01*
G01X850433Y366567D02*
X849212Y364689D01*
G01X900821Y441924D02*
X841563Y350819D01*
G01X853050Y370591D02*
X851987Y368956D01*
G01X900821Y441924D02*
X841563Y350819D01*
G01X886337Y421766D02*
X854604Y372980D01*
G01X900821Y441924D02*
X841563Y350819D01*
G01X900821Y441924D02*
X841563Y350819D01*
G01X900821Y441924D02*
X841563Y350819D01*
G01X900821Y441924D02*
X841563Y350819D01*
G01X900821Y441924D02*
X841563Y350819D01*
G01X900821Y441924D02*
X841563Y350819D01*
G01X828700Y307692D02*
X827513D01*
G01X828700Y308842D02*
X827513D01*
G01X830890Y309919D02*
G02X828700Y307692I-2190J-37D01*
G01X829740Y309900D02*
G02X828700Y308842I-1040J-18D01*
G01X830890Y335754D02*
Y309919D01*
G01X829740Y335875D02*
Y309900D01*
G01X834738Y353860D02*
X830890Y335754D01*
G01X833657Y354308D02*
X829740Y335875D01*
G01X838334Y359397D02*
X834738Y353860D01*
G01X837378Y360037D02*
X833657Y354308D01*
G01X895743Y446090D02*
X838334Y359397D01*
G01X894915Y446925D02*
X837378Y360037D01*
G01X828700Y308842D02*
X827513D01*
G01X828700Y307692D02*
X827513D01*
G01X829740Y309900D02*
G02X828700Y308842I-1040J-18D01*
G01X830890Y309919D02*
G02X828700Y307692I-2190J-37D01*
G01X829740Y335875D02*
Y309900D01*
G01X830890Y335754D02*
Y309919D01*
G01X833657Y354308D02*
X829740Y335875D01*
G01X834738Y353860D02*
X830890Y335754D01*
G01X837378Y360037D02*
X833657Y354308D01*
G01X838334Y359397D02*
X834738Y353860D01*
G01X894915Y446925D02*
X837378Y360037D01*
G01X895743Y446090D02*
X838334Y359397D01*
G01X825131Y293519D02*
X826031D01*
G01X825131Y294669D02*
X826031D01*
G01X822654Y295996D02*
G03X825131Y293519I2477J0D01*
G01X823804Y295996D02*
G03X825131Y294669I1327J0D01*
G01X822654Y333233D02*
Y295996D01*
G01X823804Y333112D02*
Y295996D01*
G01X827796Y357424D02*
X822654Y333233D01*
G01X828877Y356976D02*
X823804Y333112D01*
G01X842359Y379851D02*
X827796Y357424D01*
G01X839070Y372674D02*
X828877Y356976D01*
G01X841728Y376767D02*
X840666Y375131D01*
G01X889836Y450853D02*
X843324Y379226D01*
G01X825131Y294669D02*
X826031D01*
G01X825131Y293519D02*
X826031D01*
G01X823804Y295996D02*
G03X825131Y294669I1327J0D01*
G01X822654Y295996D02*
G03X825131Y293519I2477J0D01*
G01X823804Y333112D02*
Y295996D01*
G01X822654Y333233D02*
Y295996D01*
G01X828877Y356976D02*
X823804Y333112D01*
G01X827796Y357424D02*
X822654Y333233D01*
G01X839070Y372674D02*
X828877Y356976D01*
G01X842359Y379851D02*
X827796Y357424D01*
G01X841728Y376767D02*
X840666Y375131D01*
G01X842359Y379851D02*
X827796Y357424D01*
G01X889836Y450853D02*
X843324Y379226D01*
G01X889004Y451685D02*
X842358Y379851D01*
G01X889004Y451685D02*
X842358Y379851D01*
G01X878019Y302968D02*
X877119D01*
G01X878019Y304118D02*
X877119D01*
G01X880436Y305385D02*
G02X878019Y302968I-2417J0D01*
G01X879286Y305385D02*
G02X878019Y304118I-1267J0D01*
G01X880436Y331540D02*
Y305385D01*
G01X879286Y331881D02*
Y305385D01*
G01X929269Y406735D02*
X880436Y331540D01*
G01X928437Y407567D02*
X879286Y331881D01*
G01X878019Y304118D02*
X877119D01*
G01X878019Y302968D02*
X877119D01*
G01X879286Y305385D02*
G02X878019Y304118I-1267J0D01*
G01X880436Y305385D02*
G02X878019Y302968I-2417J0D01*
G01X879286Y331881D02*
Y305385D01*
G01X880436Y331540D02*
Y305385D01*
G01X928437Y407567D02*
X879286Y331881D01*
G01X929269Y406735D02*
X880436Y331540D01*
G01X870933Y307692D02*
X870033D01*
G01X870933Y308842D02*
X870033D01*
G01X873410Y310169D02*
G02X870933Y307692I-2477J0D01*
G01X872260Y310169D02*
G02X870933Y308842I-1327J0D01*
G01X873410Y328598D02*
Y310169D01*
G01X872260Y328719D02*
Y310169D01*
G01X876122Y341372D02*
X873410Y328598D01*
G01X875041Y341819D02*
X872260Y328719D01*
G01X925530Y417448D02*
X876122Y341372D01*
G01X884763Y356789D02*
X875041Y341819D01*
G01X887377Y360814D02*
X886315Y359179D01*
G01X902746Y384478D02*
X888930Y363205D01*
G01X870933Y308842D02*
X870033D01*
G01X870933Y307692D02*
X870033D01*
G01X872260Y310169D02*
G02X870933Y308842I-1327J0D01*
G01X873410Y310169D02*
G02X870933Y307692I-2477J0D01*
G01X872260Y328719D02*
Y310169D01*
G01X873410Y328598D02*
Y310169D01*
G01X875041Y341819D02*
X872260Y328719D01*
G01X876122Y341372D02*
X873410Y328598D01*
G01X884763Y356789D02*
X875041Y341819D01*
G01X925530Y417448D02*
X876122Y341372D01*
G01X887377Y360814D02*
X886315Y359179D01*
G01X925530Y417448D02*
X876122Y341372D01*
G01X902746Y384478D02*
X888930Y363205D01*
G01X925530Y417448D02*
X876122Y341372D01*
G01X925530Y417448D02*
X876122Y341372D01*
G01X925530Y417448D02*
X876122Y341372D01*
G01X925530Y417448D02*
X876122Y341372D01*
G01X863846Y302968D02*
X862946D01*
G01X863846Y304118D02*
X862946D01*
G01X866323Y305445D02*
G02X863846Y302968I-2477J0D01*
G01X865173Y305445D02*
G02X863846Y304118I-1327J0D01*
G01X866323Y325142D02*
Y305445D01*
G01X865173Y325263D02*
Y305445D01*
G01X870635Y345436D02*
X866323Y325142D01*
G01X869554Y345884D02*
X865173Y325263D01*
G01X920210Y421778D02*
X870635Y345436D01*
G01X870616Y347519D02*
X869554Y345884D01*
G01X873230Y351545D02*
X872168Y349910D01*
G01X897196Y388451D02*
X874782Y353935D01*
G01X863846Y304118D02*
X862946D01*
G01X863846Y302968D02*
X862946D01*
G01X865173Y305445D02*
G02X863846Y304118I-1327J0D01*
G01X866323Y305445D02*
G02X863846Y302968I-2477J0D01*
G01X865173Y325263D02*
Y305445D01*
G01X866323Y325142D02*
Y305445D01*
G01X869554Y345884D02*
X865173Y325263D01*
G01X870635Y345436D02*
X866323Y325142D01*
G01X870616Y347519D02*
X869554Y345884D01*
G01X920210Y421778D02*
X870635Y345436D01*
G01X873230Y351545D02*
X872168Y349910D01*
G01X920210Y421778D02*
X870635Y345436D01*
G01X897196Y388451D02*
X874782Y353935D01*
G01X920210Y421778D02*
X870635Y345436D01*
G01X920210Y421778D02*
X870635Y345436D01*
G01X920210Y421778D02*
X870635Y345436D01*
G01X920210Y421778D02*
X870635Y345436D01*
G01X863844Y349338D02*
X863439Y347431D01*
G01X915153Y426230D02*
X864925Y348890D01*
G01X908308Y417803D02*
X863844Y349338D01*
G01D02*
X863439Y347431D01*
G01X908308Y417803D02*
X863844Y349338D01*
G01X915153Y426230D02*
X864925Y348890D01*
G01X915153Y426230D02*
X864925Y348890D01*
G01X915153Y426230D02*
X864925Y348890D01*
G01X1097428Y515939D02*
X929269Y406735D01*
G01X935237Y411983D02*
X928437Y407567D01*
G01X939262Y414597D02*
X937627Y413535D01*
G01X960975Y428698D02*
X941653Y416149D01*
G01X935237Y411983D02*
X928437Y407567D01*
G01X1097428Y515939D02*
X929269Y406735D01*
G01X939262Y414597D02*
X937627Y413535D01*
G01X1097428Y515939D02*
X929269Y406735D01*
G01X960975Y428698D02*
X941653Y416149D01*
G01X1097428Y515939D02*
X929269Y406735D01*
G01X1097428Y515939D02*
X929269Y406735D01*
G01X1097428Y515939D02*
X929269Y406735D01*
G01X1097428Y515939D02*
X929269Y406735D01*
G01X905360Y388503D02*
X904298Y386868D01*
G01X907974Y392529D02*
X906912Y390894D01*
G01X924698Y418280D02*
X909527Y394919D01*
G01X1006815Y470236D02*
X925530Y417448D01*
G01X1087762Y524175D02*
X924698Y418280D01*
G01X1087762Y524175D02*
X924698Y418280D01*
G01X905360Y388503D02*
X904298Y386868D01*
G01X907974Y392529D02*
X906912Y390894D01*
G01X924698Y418280D02*
X909527Y394919D01*
G01X1087762Y524175D02*
X924698Y418280D01*
G01X1006815Y470236D02*
X925530Y417448D01*
G01X899810Y392476D02*
X898748Y390841D01*
G01X902424Y396502D02*
X901362Y394867D01*
G01X919378Y422610D02*
X903976Y398892D01*
G01X1087029Y530112D02*
X920210Y421778D01*
G01X1086688Y531262D02*
X919378Y422610D01*
G01X899810Y392476D02*
X898748Y390841D01*
G01X902424Y396502D02*
X901362Y394867D01*
G01X919378Y422610D02*
X903976Y398892D01*
G01X1086688Y531262D02*
X919378Y422610D01*
G01X1087029Y530112D02*
X920210Y421778D01*
G01X910923Y421829D02*
X909860Y420194D01*
G01X914321Y427062D02*
X912475Y424219D01*
G01X1086031Y537199D02*
X915153Y426230D01*
G01X1085690Y538349D02*
X914321Y427062D01*
G01X910923Y421829D02*
X909860Y420194D01*
G01X914321Y427062D02*
X912475Y424219D01*
G01X1085690Y538349D02*
X914321Y427062D01*
G01X1086031Y537199D02*
X915153Y426230D01*
G01X1085342Y544285D02*
X908884Y429681D01*
G01X909687Y431575D02*
X908052Y430513D01*
G01X913713Y434190D02*
X912078Y433127D01*
G01X1085001Y545435D02*
X916103Y435742D01*
G01X909687Y431575D02*
X908052Y430513D01*
G01X1085342Y544285D02*
X908884Y429681D01*
G01X913713Y434190D02*
X912078Y433127D01*
G01X1085342Y544285D02*
X908884Y429681D01*
G01X1085001Y545435D02*
X916103Y435742D01*
G01X1085342Y544285D02*
X908884Y429681D01*
G01X1083297Y551372D02*
X904343Y435148D01*
G01X905146Y437042D02*
X903511Y435980D01*
G01X909172Y439657D02*
X907537Y438594D01*
G01X1082956Y552522D02*
X911562Y441209D01*
G01X905146Y437042D02*
X903511Y435980D01*
G01X1083297Y551372D02*
X904343Y435148D01*
G01X909172Y439657D02*
X907537Y438594D01*
G01X1083297Y551372D02*
X904343Y435148D01*
G01X1082956Y552522D02*
X911562Y441209D01*
G01X1083297Y551372D02*
X904343Y435148D01*
G01X888954Y425791D02*
X887891Y424156D01*
G01X895183Y435366D02*
X890508Y428180D01*
G01X897520Y438959D02*
X895183Y435366D01*
G01X898688Y440755D02*
X897520Y438959D01*
G01X899990Y442756D02*
X898688Y440755D01*
G01X1080285Y558458D02*
X900821Y441924D01*
G01X1079944Y559608D02*
X899990Y442756D01*
G01X888954Y425791D02*
X887891Y424156D01*
G01X895183Y435366D02*
X890508Y428180D01*
G01X897520Y438959D02*
X895183Y435366D01*
G01X898688Y440755D02*
X897520Y438959D01*
G01X899990Y442756D02*
X898688Y440755D01*
G01X1079944Y559608D02*
X899990Y442756D01*
G01X1080285Y558458D02*
X900821Y441924D01*
G01X1052236Y547875D02*
X895744Y446092D01*
G01X921718Y464358D02*
X894914Y446925D01*
G01X925741Y466975D02*
X924107Y465912D01*
G01X929765Y469592D02*
X928130Y468529D01*
G01X1045998Y545191D02*
X932154Y471146D01*
G01X921718Y464358D02*
X894914Y446925D01*
G01X1052236Y547875D02*
X895744Y446092D01*
G01X925741Y466975D02*
X924107Y465912D01*
G01X1052236Y547875D02*
X895744Y446092D01*
G01X929765Y469592D02*
X928130Y468529D01*
G01X1052236Y547875D02*
X895744Y446092D01*
G01X1045998Y545191D02*
X932154Y471146D01*
G01X1052236Y547875D02*
X895744Y446092D01*
G01X1052236Y547875D02*
X895744Y446092D01*
G01X909001Y464693D02*
X889004Y451685D01*
G01X909610Y463716D02*
X889836Y450853D01*
G01X908930Y464693D02*
X909001D01*
G01X909610Y463716D02*
X889836Y450853D01*
G01X1076914Y573781D02*
X908930Y464693D01*
G01X913650Y466386D02*
X912015Y465324D01*
G01X917743Y469044D02*
X916108Y467982D01*
G01X921836Y471701D02*
X920200Y470639D01*
G01X970353Y503208D02*
X924293Y473297D01*
G01X909610Y463716D02*
X889836Y450853D01*
G01X909001Y464693D02*
X889004Y451685D01*
G01X908930Y464693D02*
X909001D01*
G01X913650Y466386D02*
X912015Y465324D01*
G01X1076914Y573781D02*
X908930Y464693D01*
G01X917743Y469044D02*
X916108Y467982D01*
G01X1076914Y573781D02*
X908930Y464693D01*
G01X921836Y471701D02*
X920200Y470639D01*
G01X1076914Y573781D02*
X908930Y464693D01*
G01X970353Y503208D02*
X924293Y473297D01*
G01X1076914Y573781D02*
X908930Y464693D01*
G01X1076914Y573781D02*
X908930Y464693D01*
G01X1076914Y573781D02*
X908930Y464693D01*
G01X1076914Y573781D02*
X908930Y464693D01*
G01X1076914Y573781D02*
X908930Y464693D01*
G01X1076914Y573781D02*
X908930Y464693D01*
G01X1076914Y573781D02*
X908930Y464693D01*
G01X1076914Y573781D02*
X908930Y464693D01*
G01X1076914Y573781D02*
X908930Y464693D01*
G01X965000Y431312D02*
X963365Y430250D01*
G01X969026Y433926D02*
X967390Y432864D01*
G01X1096700Y516838D02*
X971416Y435478D01*
G01X965000Y431312D02*
X963365Y430250D01*
G01X969026Y433926D02*
X967390Y432864D01*
G01X1096700Y516838D02*
X971416Y435478D01*
G01X1088103Y523025D02*
X1006815Y470236D01*
G01X1088103Y523025D02*
X1006815Y470236D01*
G01X1050022Y547808D02*
X1048387Y546745D01*
G01X1065819Y556710D02*
X1052236Y547875D01*
G01X1079061Y566695D02*
X1052411Y549362D01*
G01X1079061Y566695D02*
X1052411Y549362D01*
G01X1050022Y547808D02*
X1048387Y546745D01*
G01X1079061Y566695D02*
X1052411Y549362D01*
G01X1065819Y556710D02*
X1052236Y547875D01*
G01X974446Y505866D02*
X972811Y504804D01*
G01X978539Y508524D02*
X976903Y507462D01*
G01X982632Y511182D02*
X980996Y510120D01*
G01X1060723Y561895D02*
X985089Y512778D01*
G01X974446Y505866D02*
X972811Y504804D01*
G01X978539Y508524D02*
X976903Y507462D01*
G01X982632Y511182D02*
X980996Y510120D01*
G01X1060723Y561895D02*
X985089Y512778D01*
G01X1098751Y517262D02*
X1097428Y515939D01*
G01X1097601Y517739D02*
X1096700Y516838D01*
G01X1098751Y519302D02*
Y517262D01*
G01X1097601Y519302D02*
Y517739D01*
G01D02*
X1096700Y516838D01*
G01X1098751Y517262D02*
X1097428Y515939D01*
G01X1097601Y519302D02*
Y517739D01*
G01X1098751Y519302D02*
Y517262D01*
G01X1100113Y523025D02*
X1088103D01*
G01X1100113Y524175D02*
X1087762D01*
G01X1102688Y525600D02*
G02X1100113Y523025I-2575J0D01*
G01X1101538Y525600D02*
G02X1100113Y524175I-1425J0D01*
G01X1102688Y526388D02*
Y525600D01*
G01X1101538Y526388D02*
Y525600D01*
G01X1100113Y524175D02*
X1087762D01*
G01X1100113Y523025D02*
X1088103D01*
G01X1101538Y525600D02*
G02X1100113Y524175I-1425J0D01*
G01X1102688Y525600D02*
G02X1100113Y523025I-2575J0D01*
G01X1101538Y526388D02*
Y525600D01*
G01X1102688Y526388D02*
Y525600D01*
G01X1096176Y530112D02*
X1087029D01*
G01X1096176Y531262D02*
X1086688D01*
G01X1098751Y532687D02*
G02X1096176Y530112I-2575J0D01*
G01X1097601Y532687D02*
G02X1096176Y531262I-1425J0D01*
G01X1098751Y533475D02*
Y532687D01*
G01X1097601Y533475D02*
Y532687D01*
G01X1096176Y531262D02*
X1086688D01*
G01X1096176Y530112D02*
X1087029D01*
G01X1097601Y532687D02*
G02X1096176Y531262I-1425J0D01*
G01X1098751Y532687D02*
G02X1096176Y530112I-2575J0D01*
G01X1097601Y533475D02*
Y532687D01*
G01X1098751Y533475D02*
Y532687D01*
G01X1100113Y537199D02*
X1086031D01*
G01X1100113Y538349D02*
X1085690D01*
G01X1102688Y539774D02*
G02X1100113Y537199I-2575J0D01*
G01X1101538Y539774D02*
G02X1100113Y538349I-1425J0D01*
G01X1102688Y540562D02*
Y539774D01*
G01X1101538Y540562D02*
Y539774D01*
G01X1100113Y538349D02*
X1085690D01*
G01X1100113Y537199D02*
X1086031D01*
G01X1101538Y539774D02*
G02X1100113Y538349I-1425J0D01*
G01X1102688Y539774D02*
G02X1100113Y537199I-2575J0D01*
G01X1101538Y540562D02*
Y539774D01*
G01X1102688Y540562D02*
Y539774D01*
G01X1096176Y544285D02*
X1085342D01*
G01X1096176Y545435D02*
X1085001D01*
G01X1098751Y546860D02*
G02X1096176Y544285I-2575J0D01*
G01X1097601Y546860D02*
G02X1096176Y545435I-1425J0D01*
G01X1098751Y547648D02*
Y546860D01*
G01X1097601Y547648D02*
Y546860D01*
G01X1096176Y545435D02*
X1085001D01*
G01X1096176Y544285D02*
X1085342D01*
G01X1097601Y546860D02*
G02X1096176Y545435I-1425J0D01*
G01X1098751Y546860D02*
G02X1096176Y544285I-2575J0D01*
G01X1097601Y547648D02*
Y546860D01*
G01X1098751Y547648D02*
Y546860D01*
G01X1100113Y551372D02*
X1083297D01*
G01X1100113Y552522D02*
X1082956D01*
G01X1102688Y553947D02*
G02X1100113Y551372I-2575J0D01*
G01X1101538Y553947D02*
G02X1100113Y552522I-1425J0D01*
G01X1102688Y554735D02*
Y553947D01*
G01X1101538Y554735D02*
Y553947D01*
G01X1100113Y552522D02*
X1082956D01*
G01X1100113Y551372D02*
X1083297D01*
G01X1101538Y553947D02*
G02X1100113Y552522I-1425J0D01*
G01X1102688Y553947D02*
G02X1100113Y551372I-2575J0D01*
G01X1101538Y554735D02*
Y553947D01*
G01X1102688Y554735D02*
Y553947D01*
G01X1096176Y558458D02*
X1080285D01*
G01X1096176Y559608D02*
X1079944D01*
G01X1098751Y561033D02*
G02X1096176Y558458I-2575J0D01*
G01X1097601Y561033D02*
G02X1096176Y559608I-1425J0D01*
G01X1098751Y561821D02*
Y561033D01*
G01X1097601Y561821D02*
Y561033D01*
G01X1096176Y559608D02*
X1079944D01*
G01X1096176Y558458D02*
X1080285D01*
G01X1097601Y561033D02*
G02X1096176Y559608I-1425J0D01*
G01X1098751Y561033D02*
G02X1096176Y558458I-2575J0D01*
G01X1097601Y561821D02*
Y561033D01*
G01X1098751Y561821D02*
Y561033D01*
G01X1079403Y565545D02*
X1065819Y556710D01*
G01X1099325Y565545D02*
X1079403D01*
G01X1099325Y566695D02*
X1079061D01*
G01X1102688Y568908D02*
G02X1099325Y565545I-3363J0D01*
G01X1101538Y568908D02*
G02X1099325Y566695I-2213J0D01*
G01X1079403Y565545D02*
X1065819Y556710D01*
G01X1099325Y566695D02*
X1079061D01*
G01X1099325Y565545D02*
X1079403D01*
G01X1101538Y568908D02*
G02X1099325Y566695I-2213J0D01*
G01X1102688Y568908D02*
G02X1099325Y565545I-3363J0D01*
G01X1064816Y564552D02*
X1063180Y563490D01*
G01X1068909Y567210D02*
X1067273Y566148D01*
G01X1073001Y569868D02*
X1071366Y568806D01*
G01X1064816Y564552D02*
X1063180Y563490D01*
G01X1068909Y567210D02*
X1067273Y566148D01*
G01X1073001Y569868D02*
X1071366Y568806D01*
G01X1077094Y572526D02*
X1075459Y571464D01*
G01X1114286Y573781D02*
X1076914D01*
G01X1114286Y572631D02*
X1077448D01*
G01X1116861Y571206D02*
G03X1114286Y573781I-2575J0D01*
G01X1115711Y571206D02*
G03X1114286Y572631I-1425J0D01*
G01X1116861Y570418D02*
Y571206D01*
G01X1115711Y570418D02*
Y571206D01*
G01X1077094Y572526D02*
X1075459Y571464D01*
G01X1114286Y572631D02*
X1077448D01*
G01X1114286Y573781D02*
X1076914D01*
G01X1115711Y571206D02*
G03X1114286Y572631I-1425J0D01*
G01X1116861Y571206D02*
G03X1114286Y573781I-2575J0D01*
G01X1115711Y570418D02*
Y571206D01*
G01X1116861Y570418D02*
Y571206D01*
M02*
